G04 ================== begin FILE IDENTIFICATION RECORD ==================*
G04 Layout Name:  12004-1.brd*
G04 Film Name:    TMASK*
G04 File Format:  Gerber RS274X*
G04 File Origin:  Cadence Allegro 16.2-S033*
G04 Origin Date:  Tue Oct 16 14:35:52 2012*
G04 *
G04 Layer:  VIA CLASS/SOLDERMASK_TOP*
G04 Layer:  PIN/SOLDERMASK_TOP*
G04 Layer:  PACKAGE GEOMETRY/SOLDERMASK_TOP*
G04 Layer:  DRAWING FORMAT/LAYER_PCB_STORY*
G04 Layer:  DRAWING FORMAT/LAYER_SOLDER_T*
G04 Layer:  BOARD GEOMETRY/SOLDERMASK_TOP*
G04 *
G04 Offset:    (0.00 0.00)*
G04 Mirror:    No*
G04 Mode:      Positive*
G04 Rotation:  0*
G04 FullContactRelief:  No*
G04 UndefLineWidth:     6.00*
G04 ================== end FILE IDENTIFICATION RECORD ====================*
%FSLAX35Y35*MOIN*%
%IR0*IPPOS*OFA0.00000B0.00000*MIA0B0*SFA1.00000B1.00000*%
%AMMACRO50*
4,1,40,.017,-.013,
.017,.013,
.016939,.013695,
.016759,.014368,
.016464,.015,
.016064,.015571,
.015571,.016064,
.015,.016464,
.014368,.016759,
.013695,.016939,
.013,.017,
-.013,.017,
-.013695,.016939,
-.014368,.016759,
-.015,.016464,
-.015571,.016064,
-.016064,.015571,
-.016464,.015,
-.016759,.014368,
-.016939,.013695,
-.017,.013,
-.017,-.013,
-.016939,-.013695,
-.016759,-.014368,
-.016464,-.015,
-.016064,-.015571,
-.015571,-.016064,
-.015,-.016464,
-.014368,-.016759,
-.013695,-.016939,
-.013,-.017,
.013,-.017,
.013695,-.016939,
.014368,-.016759,
.015,-.016464,
.015571,-.016064,
.016064,-.015571,
.016464,-.015,
.016759,-.014368,
.016939,-.013695,
.017,-.013,
0.0*
%
%ADD50MACRO50*%
%AMMACRO44*
4,1,40,.013,.017,
-.013,.017,
-.013695,.016939,
-.014368,.016759,
-.015,.016464,
-.015571,.016064,
-.016064,.015571,
-.016464,.015,
-.016759,.014368,
-.016939,.013695,
-.017,.013,
-.017,-.013,
-.016939,-.013695,
-.016759,-.014368,
-.016464,-.015,
-.016064,-.015571,
-.015571,-.016064,
-.015,-.016464,
-.014368,-.016759,
-.013695,-.016939,
-.013,-.017,
.013,-.017,
.013695,-.016939,
.014368,-.016759,
.015,-.016464,
.015571,-.016064,
.016064,-.015571,
.016464,-.015,
.016759,-.014368,
.016939,-.013695,
.017,-.013,
.017,.013,
.016939,.013695,
.016759,.014368,
.016464,.015,
.016064,.015571,
.015571,.016064,
.015,.016464,
.014368,.016759,
.013695,.016939,
.013,.017,
0.0*
%
%ADD44MACRO44*%
%ADD82R,.045X.11*%
%ADD52R,.11X.055*%
%ADD36C,.02*%
%ADD92R,.126X.028*%
%ADD34C,.032*%
%ADD15C,.05*%
%ADD61R,.064X.136*%
%ADD64C,.061*%
%ADD58C,.016*%
%ADD91R,.165X.028*%
%ADD45C,.062*%
%ADD37C,.018*%
%ADD56R,.167X.09*%
%ADD35C,.055*%
%ADD27C,.028*%
%ADD14C,.046*%
%ADD13C,.079*%
%AMMACRO24*
4,1,40,.011,-.007,
.011,.007,
.010939,.007695,
.010759,.008368,
.010464,.009,
.010064,.009571,
.009571,.010064,
.009,.010464,
.008368,.010759,
.007695,.010939,
.007,.011,
-.007,.011,
-.007695,.010939,
-.008368,.010759,
-.009,.010464,
-.009571,.010064,
-.010064,.009571,
-.010464,.009,
-.010759,.008368,
-.010939,.007695,
-.011,.007,
-.011,-.007,
-.010939,-.007695,
-.010759,-.008368,
-.010464,-.009,
-.010064,-.009571,
-.009571,-.010064,
-.009,-.010464,
-.008368,-.010759,
-.007695,-.010939,
-.007,-.011,
.007,-.011,
.007695,-.010939,
.008368,-.010759,
.009,-.010464,
.009571,-.010064,
.010064,-.009571,
.010464,-.009,
.010759,-.008368,
.010939,-.007695,
.011,-.007,
0.0*
%
%ADD24MACRO24*%
%AMMACRO22*
4,1,40,.007,.011,
-.007,.011,
-.007695,.010939,
-.008368,.010759,
-.009,.010464,
-.009571,.010064,
-.010064,.009571,
-.010464,.009,
-.010759,.008368,
-.010939,.007695,
-.011,.007,
-.011,-.007,
-.010939,-.007695,
-.010759,-.008368,
-.010464,-.009,
-.010064,-.009571,
-.009571,-.010064,
-.009,-.010464,
-.008368,-.010759,
-.007695,-.010939,
-.007,-.011,
.007,-.011,
.007695,-.010939,
.008368,-.010759,
.009,-.010464,
.009571,-.010064,
.010064,-.009571,
.010464,-.009,
.010759,-.008368,
.010939,-.007695,
.011,-.007,
.011,.007,
.010939,.007695,
.010759,.008368,
.010464,.009,
.010064,.009571,
.009571,.010064,
.009,.010464,
.008368,.010759,
.007695,.010939,
.007,.011,
0.0*
%
%ADD22MACRO22*%
%AMMACRO30*
4,1,40,-.012,.008,
-.012,-.008,
-.011939,-.008695,
-.011759,-.009368,
-.011464,-.01,
-.011064,-.010571,
-.010571,-.011064,
-.01,-.011464,
-.009368,-.011759,
-.008695,-.011939,
-.008,-.012,
.008,-.012,
.008695,-.011939,
.009368,-.011759,
.01,-.011464,
.010571,-.011064,
.011064,-.010571,
.011464,-.01,
.011759,-.009368,
.011939,-.008695,
.012,-.008,
.012,.008,
.011939,.008695,
.011759,.009368,
.011464,.01,
.011064,.010571,
.010571,.011064,
.01,.011464,
.009368,.011759,
.008695,.011939,
.008,.012,
-.008,.012,
-.008695,.011939,
-.009368,.011759,
-.01,.011464,
-.010571,.011064,
-.011064,.010571,
-.011464,.01,
-.011759,.009368,
-.011939,.008695,
-.012,.008,
0.0*
%
%ADD30MACRO30*%
%AMMACRO63*
4,1,40,.008,.012,
-.008,.012,
-.008695,.011939,
-.009368,.011759,
-.01,.011464,
-.010571,.011064,
-.011064,.010571,
-.011464,.01,
-.011759,.009368,
-.011939,.008695,
-.012,.008,
-.012,-.008,
-.011939,-.008695,
-.011759,-.009368,
-.011464,-.01,
-.011064,-.010571,
-.010571,-.011064,
-.01,-.011464,
-.009368,-.011759,
-.008695,-.011939,
-.008,-.012,
.008,-.012,
.008695,-.011939,
.009368,-.011759,
.01,-.011464,
.010571,-.011064,
.011064,-.010571,
.011464,-.01,
.011759,-.009368,
.011939,-.008695,
.012,-.008,
.012,.008,
.011939,.008695,
.011759,.009368,
.011464,.01,
.011064,.010571,
.010571,.011064,
.01,.011464,
.009368,.011759,
.008695,.011939,
.008,.012,
0.0*
%
%ADD63MACRO63*%
%AMMACRO47*
4,1,40,-.013,-.017,
.013,-.017,
.013695,-.016939,
.014368,-.016759,
.015,-.016464,
.015571,-.016064,
.016064,-.015571,
.016464,-.015,
.016759,-.014368,
.016939,-.013695,
.017,-.013,
.017,.013,
.016939,.013695,
.016759,.014368,
.016464,.015,
.016064,.015571,
.015571,.016064,
.015,.016464,
.014368,.016759,
.013695,.016939,
.013,.017,
-.013,.017,
-.013695,.016939,
-.014368,.016759,
-.015,.016464,
-.015571,.016064,
-.016064,.015571,
-.016464,.015,
-.016759,.014368,
-.016939,.013695,
-.017,.013,
-.017,-.013,
-.016939,-.013695,
-.016759,-.014368,
-.016464,-.015,
-.016064,-.015571,
-.015571,-.016064,
-.015,-.016464,
-.014368,-.016759,
-.013695,-.016939,
-.013,-.017,
0.0*
%
%ADD47MACRO47*%
%AMMACRO67*
4,1,6,-.025,-.0135,
-.005,.0065,
-.005,.0135,
.005,.0135,
.005,.0065,
.025,-.0135,
-.025,-.0135,
0.0*
%
%ADD67MACRO67*%
%AMMACRO59*
4,1,40,-.017,.013,
-.017,-.013,
-.016939,-.013695,
-.016759,-.014368,
-.016464,-.015,
-.016064,-.015571,
-.015571,-.016064,
-.015,-.016464,
-.014368,-.016759,
-.013695,-.016939,
-.013,-.017,
.013,-.017,
.013695,-.016939,
.014368,-.016759,
.015,-.016464,
.015571,-.016064,
.016064,-.015571,
.016464,-.015,
.016759,-.014368,
.016939,-.013695,
.017,-.013,
.017,.013,
.016939,.013695,
.016759,.014368,
.016464,.015,
.016064,.015571,
.015571,.016064,
.015,.016464,
.014368,.016759,
.013695,.016939,
.013,.017,
-.013,.017,
-.013695,.016939,
-.014368,.016759,
-.015,.016464,
-.015571,.016064,
-.016064,.015571,
-.016464,.015,
-.016759,.014368,
-.016939,.013695,
-.017,.013,
0.0*
%
%ADD59MACRO59*%
%AMMACRO77*
4,1,6,.005,.0135,
.005,.0065,
.025,-.0135,
-.025,-.0135,
-.005,.0065,
-.005,.0135,
.005,.0135,
0.0*
%
%ADD77MACRO77*%
%AMMACRO25*
4,1,40,.011,-.007,
.011,.007,
.010939,.007695,
.010759,.008368,
.010464,.009,
.010064,.009571,
.009571,.010064,
.009,.010464,
.008368,.010759,
.007695,.010939,
.007,.011,
-.007,.011,
-.007695,.010939,
-.008368,.010759,
-.009,.010464,
-.009571,.010064,
-.010064,.009571,
-.010464,.009,
-.010759,.008368,
-.010939,.007695,
-.011,.007,
-.011,-.007,
-.010939,-.007695,
-.010759,-.008368,
-.010464,-.009,
-.010064,-.009571,
-.009571,-.010064,
-.009,-.010464,
-.008368,-.010759,
-.007695,-.010939,
-.007,-.011,
.007,-.011,
.007695,-.010939,
.008368,-.010759,
.009,-.010464,
.009571,-.010064,
.010064,-.009571,
.010464,-.009,
.010759,-.008368,
.010939,-.007695,
.011,-.007,
0.0*
%
%ADD25MACRO25*%
%AMMACRO23*
4,1,40,.007,.011,
-.007,.011,
-.007695,.010939,
-.008368,.010759,
-.009,.010464,
-.009571,.010064,
-.010064,.009571,
-.010464,.009,
-.010759,.008368,
-.010939,.007695,
-.011,.007,
-.011,-.007,
-.010939,-.007695,
-.010759,-.008368,
-.010464,-.009,
-.010064,-.009571,
-.009571,-.010064,
-.009,-.010464,
-.008368,-.010759,
-.007695,-.010939,
-.007,-.011,
.007,-.011,
.007695,-.010939,
.008368,-.010759,
.009,-.010464,
.009571,-.010064,
.010064,-.009571,
.010464,-.009,
.010759,-.008368,
.010939,-.007695,
.011,-.007,
.011,.007,
.010939,.007695,
.010759,.008368,
.010464,.009,
.010064,.009571,
.009571,.010064,
.009,.010464,
.008368,.010759,
.007695,.010939,
.007,.011,
0.0*
%
%ADD23MACRO23*%
%AMMACRO76*
4,1,20,.0635,-.1075,
.049,-.1075,
.049,-.118,
.0395,-.118,
.0395,-.1075,
-.0395,-.1075,
-.0395,-.118,
-.049,-.118,
-.049,-.1075,
-.0635,-.1075,
-.0635,.1075,
-.049,.1075,
-.049,.118,
-.0395,.118,
-.0395,.1075,
.0395,.1075,
.0395,.118,
.049,.118,
.049,.1075,
.0635,.1075,
.0635,-.1075,
0.0*
%
%ADD76MACRO76*%
%AMMACRO29*
4,1,40,-.012,.008,
-.012,-.008,
-.011939,-.008695,
-.011759,-.009368,
-.011464,-.01,
-.011064,-.010571,
-.010571,-.011064,
-.01,-.011464,
-.009368,-.011759,
-.008695,-.011939,
-.008,-.012,
.008,-.012,
.008695,-.011939,
.009368,-.011759,
.01,-.011464,
.010571,-.011064,
.011064,-.010571,
.011464,-.01,
.011759,-.009368,
.011939,-.008695,
.012,-.008,
.012,.008,
.011939,.008695,
.011759,.009368,
.011464,.01,
.011064,.010571,
.010571,.011064,
.01,.011464,
.009368,.011759,
.008695,.011939,
.008,.012,
-.008,.012,
-.008695,.011939,
-.009368,.011759,
-.01,.011464,
-.010571,.011064,
-.011064,.010571,
-.011464,.01,
-.011759,.009368,
-.011939,.008695,
-.012,.008,
0.0*
%
%ADD29MACRO29*%
%AMMACRO62*
4,1,40,.008,.012,
-.008,.012,
-.008695,.011939,
-.009368,.011759,
-.01,.011464,
-.010571,.011064,
-.011064,.010571,
-.011464,.01,
-.011759,.009368,
-.011939,.008695,
-.012,.008,
-.012,-.008,
-.011939,-.008695,
-.011759,-.009368,
-.011464,-.01,
-.011064,-.010571,
-.010571,-.011064,
-.01,-.011464,
-.009368,-.011759,
-.008695,-.011939,
-.008,-.012,
.008,-.012,
.008695,-.011939,
.009368,-.011759,
.01,-.011464,
.010571,-.011064,
.011064,-.010571,
.011464,-.01,
.011759,-.009368,
.011939,-.008695,
.012,-.008,
.012,.008,
.011939,.008695,
.011759,.009368,
.011464,.01,
.011064,.010571,
.010571,.011064,
.01,.011464,
.009368,.011759,
.008695,.011939,
.008,.012,
0.0*
%
%ADD62MACRO62*%
%AMMACRO48*
4,1,40,-.013,-.017,
.013,-.017,
.013695,-.016939,
.014368,-.016759,
.015,-.016464,
.015571,-.016064,
.016064,-.015571,
.016464,-.015,
.016759,-.014368,
.016939,-.013695,
.017,-.013,
.017,.013,
.016939,.013695,
.016759,.014368,
.016464,.015,
.016064,.015571,
.015571,.016064,
.015,.016464,
.014368,.016759,
.013695,.016939,
.013,.017,
-.013,.017,
-.013695,.016939,
-.014368,.016759,
-.015,.016464,
-.015571,.016064,
-.016064,.015571,
-.016464,.015,
-.016759,.014368,
-.016939,.013695,
-.017,.013,
-.017,-.013,
-.016939,-.013695,
-.016759,-.014368,
-.016464,-.015,
-.016064,-.015571,
-.015571,-.016064,
-.015,-.016464,
-.014368,-.016759,
-.013695,-.016939,
-.013,-.017,
0.0*
%
%ADD48MACRO48*%
%AMMACRO60*
4,1,40,-.017,.013,
-.017,-.013,
-.016939,-.013695,
-.016759,-.014368,
-.016464,-.015,
-.016064,-.015571,
-.015571,-.016064,
-.015,-.016464,
-.014368,-.016759,
-.013695,-.016939,
-.013,-.017,
.013,-.017,
.013695,-.016939,
.014368,-.016759,
.015,-.016464,
.015571,-.016064,
.016064,-.015571,
.016464,-.015,
.016759,-.014368,
.016939,-.013695,
.017,-.013,
.017,.013,
.016939,.013695,
.016759,.014368,
.016464,.015,
.016064,.015571,
.015571,.016064,
.015,.016464,
.014368,.016759,
.013695,.016939,
.013,.017,
-.013,.017,
-.013695,.016939,
-.014368,.016759,
-.015,.016464,
-.015571,.016064,
-.016064,.015571,
-.016464,.015,
-.016759,.014368,
-.016939,.013695,
-.017,.013,
0.0*
%
%ADD60MACRO60*%
%ADD80R,.06X.02*%
%ADD17R,.06X.012*%
%ADD46O,.071X.014*%
%ADD85R,.04X.016*%
%ADD83R,.06X.014*%
%ADD65R,.044X.012*%
%ADD89R,.014X.042*%
%ADD88R,.042X.014*%
%ADD79R,.014X.06*%
%ADD55R,.114X.128*%
%ADD32R,.045X.03*%
%ADD72R,.08X.05*%
%ADD69R,.038X.012*%
%ADD68R,.012X.038*%
%ADD10C,.14*%
%ADD90R,.05X.065*%
%ADD73R,.073X.07*%
%ADD49R,.065X.05*%
%ADD84R,.065X.025*%
%ADD81R,.09X.09*%
%AMMACRO70*
4,1,12,-.0405,.0405,
-.013,.0405,
-.013,.07,
.013,.07,
.013,.0405,
.0405,.0405,
.0405,-.0405,
.013,-.0405,
.013,-.07,
-.013,-.07,
-.013,-.0405,
-.0405,-.0405,
-.0405,.0405,
0.0*
%
%ADD70MACRO70*%
%ADD54R,.025X.065*%
%ADD39R,.045X.055*%
%ADD38R,.12X.12*%
%ADD75R,.083X.035*%
%ADD66R,.074X.054*%
%ADD43R,.055X.045*%
%ADD33R,.016X.048*%
%ADD74R,.073X.065*%
%ADD12C,.158*%
%ADD11R,.16X.16*%
%ADD53R,.095X.09*%
%ADD16C,.375*%
%ADD26R,.038X.095*%
%ADD86C,.197*%
%ADD57R,.087X.047*%
%ADD87R,.128X.128*%
%AMMACRO42*
4,1,40,-.008,-.012,
.008,-.012,
.008695,-.011939,
.009368,-.011759,
.01,-.011464,
.010571,-.011064,
.011064,-.010571,
.011464,-.01,
.011759,-.009368,
.011939,-.008695,
.012,-.008,
.012,.008,
.011939,.008695,
.011759,.009368,
.011464,.01,
.011064,.010571,
.010571,.011064,
.01,.011464,
.009368,.011759,
.008695,.011939,
.008,.012,
-.008,.012,
-.008695,.011939,
-.009368,.011759,
-.01,.011464,
-.010571,.011064,
-.011064,.010571,
-.011464,.01,
-.011759,.009368,
-.011939,.008695,
-.012,.008,
-.012,-.008,
-.011939,-.008695,
-.011759,-.009368,
-.011464,-.01,
-.011064,-.010571,
-.010571,-.011064,
-.01,-.011464,
-.009368,-.011759,
-.008695,-.011939,
-.008,-.012,
0.0*
%
%ADD42MACRO42*%
%AMMACRO28*
4,1,40,.012,-.008,
.012,.008,
.011939,.008695,
.011759,.009368,
.011464,.01,
.011064,.010571,
.010571,.011064,
.01,.011464,
.009368,.011759,
.008695,.011939,
.008,.012,
-.008,.012,
-.008695,.011939,
-.009368,.011759,
-.01,.011464,
-.010571,.011064,
-.011064,.010571,
-.011464,.01,
-.011759,.009368,
-.011939,.008695,
-.012,.008,
-.012,-.008,
-.011939,-.008695,
-.011759,-.009368,
-.011464,-.01,
-.011064,-.010571,
-.010571,-.011064,
-.01,-.011464,
-.009368,-.011759,
-.008695,-.011939,
-.008,-.012,
.008,-.012,
.008695,-.011939,
.009368,-.011759,
.01,-.011464,
.010571,-.011064,
.011064,-.010571,
.011464,-.01,
.011759,-.009368,
.011939,-.008695,
.012,-.008,
0.0*
%
%ADD28MACRO28*%
%AMMACRO20*
4,1,40,-.007,-.011,
.007,-.011,
.007695,-.010939,
.008368,-.010759,
.009,-.010464,
.009571,-.010064,
.010064,-.009571,
.010464,-.009,
.010759,-.008368,
.010939,-.007695,
.011,-.007,
.011,.007,
.010939,.007695,
.010759,.008368,
.010464,.009,
.010064,.009571,
.009571,.010064,
.009,.010464,
.008368,.010759,
.007695,.010939,
.007,.011,
-.007,.011,
-.007695,.010939,
-.008368,.010759,
-.009,.010464,
-.009571,.010064,
-.010064,.009571,
-.010464,.009,
-.010759,.008368,
-.010939,.007695,
-.011,.007,
-.011,-.007,
-.010939,-.007695,
-.010759,-.008368,
-.010464,-.009,
-.010064,-.009571,
-.009571,-.010064,
-.009,-.010464,
-.008368,-.010759,
-.007695,-.010939,
-.007,-.011,
0.0*
%
%ADD20MACRO20*%
%AMMACRO18*
4,1,40,-.011,.007,
-.011,-.007,
-.010939,-.007695,
-.010759,-.008368,
-.010464,-.009,
-.010064,-.009571,
-.009571,-.010064,
-.009,-.010464,
-.008368,-.010759,
-.007695,-.010939,
-.007,-.011,
.007,-.011,
.007695,-.010939,
.008368,-.010759,
.009,-.010464,
.009571,-.010064,
.010064,-.009571,
.010464,-.009,
.010759,-.008368,
.010939,-.007695,
.011,-.007,
.011,.007,
.010939,.007695,
.010759,.008368,
.010464,.009,
.010064,.009571,
.009571,.010064,
.009,.010464,
.008368,.010759,
.007695,.010939,
.007,.011,
-.007,.011,
-.007695,.010939,
-.008368,.010759,
-.009,.010464,
-.009571,.010064,
-.010064,.009571,
-.010464,.009,
-.010759,.008368,
-.010939,.007695,
-.011,.007,
0.0*
%
%ADD18MACRO18*%
%AMMACRO78*
4,1,6,.025,.0135,
.005,-.0065,
.005,-.0135,
-.005,-.0135,
-.005,-.0065,
-.025,.0135,
.025,.0135,
0.0*
%
%ADD78MACRO78*%
%AMMACRO51*
4,1,40,.017,-.013,
.017,.013,
.016939,.013695,
.016759,.014368,
.016464,.015,
.016064,.015571,
.015571,.016064,
.015,.016464,
.014368,.016759,
.013695,.016939,
.013,.017,
-.013,.017,
-.013695,.016939,
-.014368,.016759,
-.015,.016464,
-.015571,.016064,
-.016064,.015571,
-.016464,.015,
-.016759,.014368,
-.016939,.013695,
-.017,.013,
-.017,-.013,
-.016939,-.013695,
-.016759,-.014368,
-.016464,-.015,
-.016064,-.015571,
-.015571,-.016064,
-.015,-.016464,
-.014368,-.016759,
-.013695,-.016939,
-.013,-.017,
.013,-.017,
.013695,-.016939,
.014368,-.016759,
.015,-.016464,
.015571,-.016064,
.016064,-.015571,
.016464,-.015,
.016759,-.014368,
.016939,-.013695,
.017,-.013,
0.0*
%
%ADD51MACRO51*%
%AMMACRO31*
4,1,40,.013,.017,
-.013,.017,
-.013695,.016939,
-.014368,.016759,
-.015,.016464,
-.015571,.016064,
-.016064,.015571,
-.016464,.015,
-.016759,.014368,
-.016939,.013695,
-.017,.013,
-.017,-.013,
-.016939,-.013695,
-.016759,-.014368,
-.016464,-.015,
-.016064,-.015571,
-.015571,-.016064,
-.015,-.016464,
-.014368,-.016759,
-.013695,-.016939,
-.013,-.017,
.013,-.017,
.013695,-.016939,
.014368,-.016759,
.015,-.016464,
.015571,-.016064,
.016064,-.015571,
.016464,-.015,
.016759,-.014368,
.016939,-.013695,
.017,-.013,
.017,.013,
.016939,.013695,
.016759,.014368,
.016464,.015,
.016064,.015571,
.015571,.016064,
.015,.016464,
.014368,.016759,
.013695,.016939,
.013,.017,
0.0*
%
%ADD31MACRO31*%
%AMMACRO71*
4,1,6,-.005,-.0135,
-.005,-.0065,
-.025,.0135,
.025,.0135,
.005,-.0065,
.005,-.0135,
-.005,-.0135,
0.0*
%
%ADD71MACRO71*%
%AMMACRO41*
4,1,40,-.008,-.012,
.008,-.012,
.008695,-.011939,
.009368,-.011759,
.01,-.011464,
.010571,-.011064,
.011064,-.010571,
.011464,-.01,
.011759,-.009368,
.011939,-.008695,
.012,-.008,
.012,.008,
.011939,.008695,
.011759,.009368,
.011464,.01,
.011064,.010571,
.010571,.011064,
.01,.011464,
.009368,.011759,
.008695,.011939,
.008,.012,
-.008,.012,
-.008695,.011939,
-.009368,.011759,
-.01,.011464,
-.010571,.011064,
-.011064,.010571,
-.011464,.01,
-.011759,.009368,
-.011939,.008695,
-.012,.008,
-.012,-.008,
-.011939,-.008695,
-.011759,-.009368,
-.011464,-.01,
-.011064,-.010571,
-.010571,-.011064,
-.01,-.011464,
-.009368,-.011759,
-.008695,-.011939,
-.008,-.012,
0.0*
%
%ADD41MACRO41*%
%AMMACRO40*
4,1,40,.012,-.008,
.012,.008,
.011939,.008695,
.011759,.009368,
.011464,.01,
.011064,.010571,
.010571,.011064,
.01,.011464,
.009368,.011759,
.008695,.011939,
.008,.012,
-.008,.012,
-.008695,.011939,
-.009368,.011759,
-.01,.011464,
-.010571,.011064,
-.011064,.010571,
-.011464,.01,
-.011759,.009368,
-.011939,.008695,
-.012,.008,
-.012,-.008,
-.011939,-.008695,
-.011759,-.009368,
-.011464,-.01,
-.011064,-.010571,
-.010571,-.011064,
-.01,-.011464,
-.009368,-.011759,
-.008695,-.011939,
-.008,-.012,
.008,-.012,
.008695,-.011939,
.009368,-.011759,
.01,-.011464,
.010571,-.011064,
.011064,-.010571,
.011464,-.01,
.011759,-.009368,
.011939,-.008695,
.012,-.008,
0.0*
%
%ADD40MACRO40*%
%AMMACRO21*
4,1,40,-.007,-.011,
.007,-.011,
.007695,-.010939,
.008368,-.010759,
.009,-.010464,
.009571,-.010064,
.010064,-.009571,
.010464,-.009,
.010759,-.008368,
.010939,-.007695,
.011,-.007,
.011,.007,
.010939,.007695,
.010759,.008368,
.010464,.009,
.010064,.009571,
.009571,.010064,
.009,.010464,
.008368,.010759,
.007695,.010939,
.007,.011,
-.007,.011,
-.007695,.010939,
-.008368,.010759,
-.009,.010464,
-.009571,.010064,
-.010064,.009571,
-.010464,.009,
-.010759,.008368,
-.010939,.007695,
-.011,.007,
-.011,-.007,
-.010939,-.007695,
-.010759,-.008368,
-.010464,-.009,
-.010064,-.009571,
-.009571,-.010064,
-.009,-.010464,
-.008368,-.010759,
-.007695,-.010939,
-.007,-.011,
0.0*
%
%ADD21MACRO21*%
%AMMACRO19*
4,1,40,-.011,.007,
-.011,-.007,
-.010939,-.007695,
-.010759,-.008368,
-.010464,-.009,
-.010064,-.009571,
-.009571,-.010064,
-.009,-.010464,
-.008368,-.010759,
-.007695,-.010939,
-.007,-.011,
.007,-.011,
.007695,-.010939,
.008368,-.010759,
.009,-.010464,
.009571,-.010064,
.010064,-.009571,
.010464,-.009,
.010759,-.008368,
.010939,-.007695,
.011,-.007,
.011,.007,
.010939,.007695,
.010759,.008368,
.010464,.009,
.010064,.009571,
.009571,.010064,
.009,.010464,
.008368,.010759,
.007695,.010939,
.007,.011,
-.007,.011,
-.007695,.010939,
-.008368,.010759,
-.009,.010464,
-.009571,.010064,
-.010064,.009571,
-.010464,.009,
-.010759,.008368,
-.010939,.007695,
-.011,.007,
0.0*
%
%ADD19MACRO19*%
%ADD93C,.006*%
G75*
%LPD*%
G75*
G36*
G01X152810Y206599D02*
X141510D01*
Y196499D01*
X152810D01*
Y206599D01*
G37*
G36*
G01Y193899D02*
X141510D01*
Y183799D01*
X152810D01*
Y193899D01*
G37*
G36*
G01X78701Y791458D02*
X100293D01*
Y801694D01*
X78701D01*
Y791458D01*
G37*
G36*
G01Y804292D02*
X95237D01*
Y812899D01*
X78701D01*
Y804292D01*
G37*
G36*
G01Y815499D02*
X95237D01*
Y824106D01*
X78701D01*
Y815499D01*
G37*
G36*
G01Y826706D02*
X95237D01*
Y835313D01*
X78701D01*
Y826706D01*
G37*
G36*
G01X118518Y801694D02*
X140543D01*
Y799712D01*
G03X149143I4300J-933D01*
G01Y801694D01*
X159343D01*
Y791458D01*
X118518D01*
Y801694D01*
G37*
G36*
G01X78701Y837913D02*
X95237D01*
Y846520D01*
X78701D01*
Y837913D01*
G37*
G36*
G01Y849120D02*
X95237D01*
Y857727D01*
X78701D01*
Y849120D01*
G37*
G36*
G01Y860327D02*
X95237D01*
Y868934D01*
X78701D01*
Y860327D01*
G37*
G36*
G01Y871534D02*
X100293D01*
Y881770D01*
X78701D01*
Y871534D01*
G37*
G36*
G01X118518Y881770D02*
X159368D01*
Y871534D01*
X149143D01*
Y873516D01*
G03X140543I-4300J933D01*
G01Y871534D01*
X118518D01*
Y881770D01*
G37*
G36*
G01X166710Y193899D02*
X155410D01*
Y183799D01*
X166710D01*
Y193899D01*
G37*
G36*
G01Y206599D02*
X155410D01*
Y196499D01*
X166710D01*
Y206599D01*
G37*
G36*
G01X221108Y157068D02*
Y152068D01*
X213108D01*
Y157068D01*
X221108D01*
G37*
G36*
G01X177593Y801694D02*
X190393D01*
Y820276D01*
X198701D01*
Y791458D01*
X177593D01*
Y801694D01*
G37*
G36*
G01X177568Y871534D02*
X190393D01*
Y854526D01*
X198701D01*
Y881770D01*
X177568D01*
Y871534D01*
G37*
G36*
G01X243608Y161568D02*
X235608D01*
Y147568D01*
X243608D01*
Y161568D01*
G37*
G36*
G01X795276Y328170D02*
Y660060D01*
X773264D01*
Y328170D01*
X795276D01*
G37*
G36*
G01Y737619D02*
Y817541D01*
X773264D01*
Y737619D01*
X795276D01*
G37*
G54D10*
X-1011811Y-15748D03*
Y940945D03*
X775591Y-15748D03*
Y940944D03*
G54D20*
X48500Y93600D03*
X66863Y267083D03*
X59263D03*
X66363Y272683D03*
X66863Y258783D03*
X59263Y258883D03*
X66863Y254683D03*
X59263Y251483D03*
X67063Y250483D03*
Y246283D03*
X59146Y242114D03*
X66963Y242083D03*
X67063Y237683D03*
X66863Y262883D03*
X66801Y294778D03*
Y290678D03*
X58863Y285083D03*
X66496Y285730D03*
Y281630D03*
X58863Y276783D03*
X66363D03*
X50680Y373862D03*
X66222Y517540D03*
X55179Y521570D03*
X43855Y517250D03*
X77242Y521666D03*
X91241Y203800D03*
X118571Y206661D03*
X143553Y331742D03*
X132417Y335856D03*
X120955Y331729D03*
X132863Y517903D03*
X88362Y517603D03*
X99385Y521826D03*
X110607Y517857D03*
X121751Y522079D03*
X143912Y522038D03*
X206425Y98053D03*
X154552Y335814D03*
X176638Y344153D03*
X165585Y339913D03*
X209880Y356594D03*
X198838Y352449D03*
X187757Y348289D03*
X192966Y481243D03*
X177049Y517848D03*
X154874Y517879D03*
X165905Y522020D03*
X210263Y522003D03*
X199063Y517803D03*
X188063Y522003D03*
X221359Y106010D03*
X250115Y93933D03*
X250090Y89833D03*
X248046Y77735D03*
X248190Y102533D03*
X248052Y73668D03*
X227102Y214585D03*
X252553Y387029D03*
X221085Y363914D03*
X246097Y432409D03*
X238700Y482954D03*
X234562Y779010D03*
X234666Y783159D03*
X234621Y787335D03*
X285742Y794780D03*
X338146Y793055D03*
X353927Y792923D03*
X308899Y794862D03*
X319115Y795010D03*
X297576Y794808D03*
X490830Y532955D03*
X490838Y541335D03*
X490523Y549911D03*
X478687Y490049D03*
X460541Y490002D03*
X490899Y508498D03*
X490902Y512828D03*
X450818Y508324D03*
X508100Y389700D03*
X511734Y424179D03*
X528810Y531644D03*
X528788Y527470D03*
X711409Y453923D03*
X661009Y474323D03*
X665109Y470223D03*
X677509Y457923D03*
X681909Y453723D03*
X692400Y537000D03*
X732109Y474523D03*
X727909Y470223D03*
X715509Y458023D03*
X729191Y857331D03*
G54D11*
X-944882Y-17185D03*
Y942382D03*
X708683Y-17218D03*
G54D21*
X45100Y93600D03*
X63463Y267083D03*
X55863D03*
X62963Y272683D03*
X63463Y258783D03*
X55863Y258883D03*
X63463Y254683D03*
X55863Y251483D03*
X63663Y250483D03*
Y246283D03*
X55746Y242114D03*
X63563Y242083D03*
X63663Y237683D03*
X63463Y262883D03*
X63401Y294778D03*
Y290678D03*
X55463Y285083D03*
X63096Y285730D03*
Y281630D03*
X55463Y276783D03*
X62963D03*
X47280Y373862D03*
X62822Y517540D03*
X51779Y521570D03*
X40455Y517250D03*
X73842Y521666D03*
X87841Y203800D03*
X115171Y206661D03*
X140153Y331742D03*
X129017Y335856D03*
X117555Y331729D03*
X129463Y517903D03*
X84962Y517603D03*
X95985Y521826D03*
X107207Y517857D03*
X118351Y522079D03*
X140512Y522038D03*
X217959Y106010D03*
X203025Y98053D03*
X151152Y335814D03*
X173238Y344153D03*
X162185Y339913D03*
X206480Y356594D03*
X217685Y363914D03*
X195438Y352449D03*
X184357Y348289D03*
X189566Y481243D03*
X173649Y517848D03*
X151474Y517879D03*
X162505Y522020D03*
X206863Y522003D03*
X195663Y517803D03*
X184663Y522003D03*
X246715Y93933D03*
X246690Y89833D03*
X244646Y77735D03*
X244790Y102533D03*
X244652Y73668D03*
X223702Y214585D03*
X249153Y387029D03*
X242697Y432409D03*
X235300Y482954D03*
X231162Y779010D03*
X231266Y783159D03*
X231221Y787335D03*
X282342Y794780D03*
X334746Y793055D03*
X350527Y792923D03*
X305499Y794862D03*
X315715Y795010D03*
X294176Y794808D03*
X487430Y532955D03*
X487438Y541335D03*
X487123Y549911D03*
X475287Y490049D03*
X457141Y490002D03*
X487499Y508498D03*
X487502Y512828D03*
X447418Y508324D03*
X504700Y389700D03*
X508334Y424179D03*
X525410Y531644D03*
X525388Y527470D03*
X708009Y453923D03*
X657609Y474323D03*
X712109Y458023D03*
X661709Y470223D03*
X674109Y457923D03*
X678509Y453723D03*
X689000Y537000D03*
X728709Y474523D03*
X724509Y470223D03*
X725791Y857331D03*
G54D12*
X-59094Y277559D03*
X-7913D03*
X109410Y796831D03*
Y876397D03*
X168465Y796831D03*
Y876397D03*
G54D30*
X47360Y172352D03*
X73400Y180800D03*
X106641Y203500D03*
X118641Y202800D03*
X148200Y233900D03*
X217790Y98033D03*
X203161Y113456D03*
X192763Y240983D03*
X192721Y244556D03*
X192763Y248183D03*
Y237383D03*
X188909Y421839D03*
X193066Y493343D03*
X253382Y399333D03*
X252641Y383206D03*
X245155Y375055D03*
X245130Y371576D03*
X249465Y363969D03*
X249428Y360456D03*
X241100Y454700D03*
X226999Y778667D03*
X490803Y501502D03*
X490818Y494161D03*
X490823Y497927D03*
X519516Y424009D03*
X521052Y552477D03*
X521213Y548807D03*
X696939Y759399D03*
X696992Y762972D03*
X698027Y817304D03*
X697975Y820842D03*
G54D40*
X27990Y497166D03*
X80800Y199800D03*
X99041Y203600D03*
X219061Y461171D03*
X219034Y464704D03*
X233200Y454700D03*
X298500Y466600D03*
X478728Y493916D03*
X460520Y493874D03*
G54D31*
X77688Y184954D03*
X24894Y493063D03*
X149631Y176850D03*
X157313Y171759D03*
X208182Y427789D03*
X211343Y418666D03*
X244700Y461100D03*
X235756Y478217D03*
X236673Y468923D03*
X299174Y475788D03*
X294700Y462500D03*
X299213Y471007D03*
G54D22*
X45100Y89400D03*
X45200Y82900D03*
X72569Y219284D03*
X70277Y517540D03*
X59282Y521602D03*
X48002Y517237D03*
X63807Y647187D03*
X64298Y761923D03*
X149282Y164664D03*
X110971Y182699D03*
X84700Y141100D03*
X115141Y199000D03*
X117341Y194500D03*
X147610Y331731D03*
X136517Y335856D03*
X125273Y331655D03*
X136963Y517903D03*
X81425Y521698D03*
X92450Y517603D03*
X103504Y521857D03*
X114725Y517858D03*
X125800Y522071D03*
X147954Y522037D03*
X214222Y101900D03*
X203020Y93789D03*
X201664Y85481D03*
X203290Y102533D03*
X160361Y145062D03*
X159849Y176397D03*
X176482Y271928D03*
X176343Y267018D03*
X177356Y261409D03*
X175709Y256562D03*
X175577Y251228D03*
X175450Y246422D03*
X173990Y237502D03*
Y241702D03*
X176410Y281361D03*
X176443Y276656D03*
X176610Y294061D03*
X176510Y285561D03*
X176610Y289861D03*
X158681Y335850D03*
X180738Y344153D03*
X169685Y339913D03*
X214080Y356594D03*
X202938Y352449D03*
X191857Y348289D03*
X212100Y449700D03*
X189566Y485443D03*
Y489543D03*
X181104Y517848D03*
X158967Y517830D03*
X170087Y522020D03*
X214463Y521903D03*
X203263Y517803D03*
X192163Y522003D03*
X244790Y98033D03*
X223666Y218917D03*
X232758Y405205D03*
X249809Y403106D03*
X225139Y363907D03*
X242703Y428291D03*
X235199Y461252D03*
X235316Y473688D03*
X358000Y792962D03*
X342834Y792836D03*
X458763Y514834D03*
X466395D03*
X487437Y528628D03*
X487483Y537159D03*
X487213Y545645D03*
X487366Y489976D03*
X529300Y393000D03*
X645700Y394600D03*
X670009Y462023D03*
X653509Y478423D03*
X649409Y482723D03*
X665909Y466123D03*
X688300Y544300D03*
X732809Y478623D03*
X736909Y482823D03*
X720409Y466123D03*
X716309Y462023D03*
X747300Y546500D03*
X749500Y555900D03*
Y551800D03*
X749600Y577500D03*
X749530Y569233D03*
X749537Y560714D03*
X749629Y573387D03*
X725800Y853200D03*
G54D13*
X-33503Y269685D03*
G54D41*
X77453Y525824D03*
X69970Y521539D03*
X66497Y521555D03*
X59007Y525728D03*
X55470Y525648D03*
X47790Y521300D03*
X44031Y521396D03*
X136663Y521903D03*
X133163Y522003D03*
X147678Y526068D03*
X144206Y526034D03*
X125501Y526046D03*
X122044Y526062D03*
X114546Y521952D03*
X110786Y521951D03*
X103330Y525965D03*
X99797Y525846D03*
X92158Y521634D03*
X88606Y521633D03*
X81117Y525760D03*
X204811Y77927D03*
X153061Y168712D03*
X219655Y214498D03*
X200498Y388564D03*
X205667Y406683D03*
X214163Y526003D03*
X210563Y526103D03*
X202963Y521903D03*
X199363D03*
X191863Y526203D03*
X188363D03*
X180845Y521911D03*
X177324Y521927D03*
X169812Y526147D03*
X166180Y526146D03*
X158691Y521893D03*
X155181Y521942D03*
X258530Y81926D03*
X243200Y520700D03*
X277254Y845565D03*
X337612Y430423D03*
X341344D03*
X360415D03*
X356714D03*
X352814D03*
X348914D03*
X345014D03*
X387100D03*
X383102D03*
X371187D03*
X367432D03*
X363968D03*
X379184D03*
X375464D03*
G54D32*
X73943Y205660D03*
Y213410D03*
X72930Y633923D03*
Y641673D03*
X65430Y637798D03*
X72814Y652628D03*
Y660378D03*
X65314Y656503D03*
X73412Y748676D03*
Y756426D03*
X65912Y752551D03*
X73356Y767193D03*
Y774943D03*
X65856Y771068D03*
X81443Y209535D03*
G54D23*
X48500Y89400D03*
X48600Y82900D03*
X75969Y219284D03*
X73677Y517540D03*
X62682Y521602D03*
X51402Y517237D03*
X67207Y647187D03*
X67698Y761923D03*
X114371Y182699D03*
X88100Y141100D03*
X118541Y199000D03*
X120741Y194500D03*
X139917Y335856D03*
X128673Y331655D03*
X140363Y517903D03*
X84825Y521698D03*
X95850Y517603D03*
X106904Y521857D03*
X118125Y517858D03*
X129200Y522071D03*
X217622Y101900D03*
X206420Y93789D03*
X205064Y85481D03*
X206690Y102533D03*
X152682Y164664D03*
X163761Y145062D03*
X163249Y176397D03*
X179882Y271928D03*
X179743Y267018D03*
X180756Y261409D03*
X179109Y256562D03*
X178977Y251228D03*
X178850Y246422D03*
X177390Y237502D03*
Y241702D03*
X179810Y281361D03*
X179843Y276656D03*
X180010Y294061D03*
X179910Y285561D03*
X180010Y289861D03*
X162081Y335850D03*
X151010Y331731D03*
X184138Y344153D03*
X173085Y339913D03*
X217480Y356594D03*
X206338Y352449D03*
X195257Y348289D03*
X215500Y449700D03*
X192966Y485443D03*
Y489543D03*
X184504Y517848D03*
X151354Y522037D03*
X162367Y517830D03*
X173487Y522020D03*
X217863Y521903D03*
X206663Y517803D03*
X195563Y522003D03*
X248190Y98033D03*
X227066Y218917D03*
X236158Y405205D03*
X253209Y403106D03*
X228539Y363907D03*
X246103Y428291D03*
X238599Y461252D03*
X238716Y473688D03*
X346234Y792836D03*
X361400Y792962D03*
X462163Y514834D03*
X469795D03*
X490837Y528628D03*
X490883Y537159D03*
X490613Y545645D03*
X490766Y489976D03*
X532700Y393000D03*
X649100Y394600D03*
X673409Y462023D03*
X656909Y478423D03*
X652809Y482723D03*
X669309Y466123D03*
X691700Y544300D03*
X736209Y478623D03*
X740309Y482823D03*
X723809Y466123D03*
X719709Y462023D03*
X750700Y546500D03*
X752900Y555900D03*
Y551800D03*
X753000Y577500D03*
X752930Y569233D03*
X752937Y560714D03*
X753029Y573387D03*
X729200Y853200D03*
G54D14*
X6614Y553544D03*
X10551Y623622D03*
X6614Y671654D03*
X10551Y741732D03*
X18425Y553544D03*
X32204D03*
X18425Y623622D03*
X32204D03*
X18425Y671654D03*
X32204D03*
X18425Y741732D03*
X32204D03*
G54D50*
X59800Y764900D03*
X93130Y145135D03*
X212000Y171900D03*
X201547Y407074D03*
X207141Y386759D03*
X185614Y458881D03*
X215006Y438401D03*
X190714Y458681D03*
X247262Y519409D03*
G54D51*
X59800Y770500D03*
X93130Y150735D03*
X212000Y177500D03*
X201547Y412674D03*
X207141Y392359D03*
X185614Y464481D03*
X215006Y444001D03*
X190714Y464281D03*
X247262Y525009D03*
G54D42*
X77453Y529424D03*
X69970Y525139D03*
X66497Y525155D03*
X59007Y529328D03*
X55470Y529248D03*
X47790Y524900D03*
X44031Y524996D03*
X136663Y525503D03*
X133163Y525603D03*
X147678Y529668D03*
X144206Y529634D03*
X125501Y529646D03*
X122044Y529662D03*
X114546Y525552D03*
X110786Y525551D03*
X103330Y529565D03*
X99797Y529446D03*
X92158Y525234D03*
X88606Y525233D03*
X81117Y529360D03*
X204811Y81527D03*
X153061Y172312D03*
X219655Y218098D03*
X200498Y392164D03*
X205667Y410283D03*
X214163Y529603D03*
X210563Y529703D03*
X202963Y525503D03*
X199363D03*
X191863Y529803D03*
X188363D03*
X180845Y525511D03*
X177324Y525527D03*
X169812Y529747D03*
X166180Y529746D03*
X158691Y525493D03*
X155181Y525542D03*
X258530Y85526D03*
X243200Y524300D03*
X277254Y849165D03*
X337612Y434023D03*
X341344D03*
X360415D03*
X356714D03*
X352814D03*
X348914D03*
X345014D03*
X387100D03*
X383102D03*
X371187D03*
X367432D03*
X363968D03*
X379184D03*
X375464D03*
G54D33*
X71660Y193550D03*
X69100D03*
X66540D03*
Y187050D03*
X71660D03*
G54D60*
X104382Y218214D03*
X99525Y218210D03*
X212700Y135300D03*
X168084Y177655D03*
X212492Y408633D03*
X217363Y407378D03*
X185934Y475829D03*
X203439Y464952D03*
X194624Y427063D03*
X190765Y475928D03*
X222577Y528119D03*
X264353Y490534D03*
X341430Y468751D03*
X371408Y399155D03*
X366586D03*
X361719D03*
G54D24*
X63000Y103300D03*
X67300D03*
X50963Y382383D03*
X46763Y397883D03*
X50830Y397889D03*
X50963Y390183D03*
X46763Y390483D03*
X61563Y374283D03*
X60122Y754461D03*
X107783Y86561D03*
X91178Y211333D03*
X80326Y658988D03*
X79967Y643494D03*
X80653Y758647D03*
X80415Y776333D03*
X208612Y81430D03*
X219504Y181570D03*
X177087Y175433D03*
X185215Y418033D03*
X185266Y493043D03*
X219303Y748114D03*
X229613Y64898D03*
X223817Y181608D03*
X235414Y217713D03*
X240662Y387084D03*
X241728Y360156D03*
X237455Y371255D03*
X238000Y418100D03*
X227900Y418000D03*
X242700Y440000D03*
X232100Y418000D03*
X223658Y748114D03*
X234524Y774783D03*
X447090Y503842D03*
X504027Y412875D03*
X504094Y405332D03*
X503981Y420419D03*
X525463Y545933D03*
X665909Y466123D03*
X649409Y482723D03*
X670009Y462023D03*
X653509Y478423D03*
X711409Y453923D03*
X650700Y532900D03*
X689190Y771506D03*
X715509Y457923D03*
X732109Y474523D03*
X727909Y470223D03*
G54D15*
X22980Y59055D03*
X30854D03*
X22980Y106299D03*
Y98425D03*
Y90551D03*
Y82677D03*
Y74803D03*
Y66929D03*
X30854Y106299D03*
Y98425D03*
Y90551D03*
Y82677D03*
Y74803D03*
Y66929D03*
X41142Y135669D03*
Y155669D03*
Y145669D03*
X26181Y537559D03*
Y527559D03*
Y517559D03*
X41142Y655669D03*
Y645669D03*
Y635669D03*
Y763780D03*
Y753780D03*
Y773780D03*
G54D16*
X29528Y19685D03*
X76772D03*
X108268Y905512D03*
X155512D03*
G54D43*
X33845Y507529D03*
Y499929D03*
X41797Y500609D03*
Y508209D03*
X99375Y144069D03*
Y151669D03*
X123397Y144069D03*
Y151669D03*
X115601Y144069D03*
Y151669D03*
X107672Y144069D03*
Y151669D03*
X174950Y133259D03*
X183700Y133300D03*
X183034Y162805D03*
Y170405D03*
X197209Y165797D03*
Y158197D03*
X174950Y140859D03*
X183700Y140900D03*
X205600Y165800D03*
Y158200D03*
X194877Y385099D03*
Y392699D03*
X187165Y385235D03*
Y392835D03*
X195311Y407990D03*
Y415590D03*
X215284Y382027D03*
Y389627D03*
X200959Y429749D03*
Y422149D03*
X197214Y464181D03*
Y456581D03*
X238000Y60400D03*
Y52800D03*
X263100Y60400D03*
Y52800D03*
X254900Y60400D03*
Y52800D03*
X246400Y60400D03*
Y52800D03*
X223321Y389661D03*
Y382061D03*
X254182Y496347D03*
Y503947D03*
X237203Y519878D03*
Y527478D03*
X261424Y519113D03*
Y526713D03*
X253508Y519183D03*
Y526783D03*
X238118Y504116D03*
Y496516D03*
X246132Y504110D03*
Y496510D03*
X262501Y504118D03*
Y496518D03*
X229241Y527601D03*
Y520001D03*
G54D70*
X167349Y158097D03*
G54D25*
X63000Y99900D03*
X67300D03*
X50963Y378983D03*
X46763Y394483D03*
X50830Y394489D03*
X50963Y386783D03*
X46763Y387083D03*
X61563Y370883D03*
X60122Y751061D03*
X107783Y83161D03*
X91178Y207933D03*
X80326Y655588D03*
X79967Y640094D03*
X80653Y755247D03*
X80415Y772933D03*
X208612Y78030D03*
X219504Y178170D03*
X177087Y172033D03*
X185215Y414633D03*
X185266Y489643D03*
X219303Y744714D03*
X229613Y61498D03*
X223817Y178208D03*
X235414Y214313D03*
X238000Y414700D03*
X227900Y414600D03*
X232100D03*
X240662Y383684D03*
X241728Y356756D03*
X237455Y367855D03*
X242700Y436600D03*
X223658Y744714D03*
X234524Y771383D03*
X447090Y500442D03*
X504027Y409475D03*
X504094Y401932D03*
X503981Y417019D03*
X525463Y542533D03*
X665909Y462723D03*
X649409Y479323D03*
X670009Y458623D03*
X653509Y475023D03*
X711409Y450523D03*
X650700Y529500D03*
X689190Y768106D03*
X715509Y454523D03*
X732109Y471123D03*
X727909Y466823D03*
G54D61*
X140847Y223231D03*
X162963D03*
G54D34*
X72915Y261033D03*
X52081Y407029D03*
X43512Y406131D03*
X40615Y397833D03*
X71815Y373833D03*
X44515Y482933D03*
X52315Y497433D03*
X51015Y491933D03*
X49815Y502633D03*
X43515Y490933D03*
X142615Y167533D03*
X119300Y181500D03*
X219115Y62233D03*
X155600Y139000D03*
X200015Y250333D03*
X192615Y254537D03*
X188615Y262433D03*
X196015Y265433D03*
X196215Y274233D03*
X187601Y275296D03*
X193115Y282033D03*
X186663Y450083D03*
X186363Y444183D03*
X186016Y432468D03*
X192815Y433733D03*
X198615Y449033D03*
X193915Y441633D03*
X186163Y438083D03*
X235215Y182933D03*
X235715Y755233D03*
X325013Y789701D03*
X333871Y786092D03*
X451015Y514433D03*
X680100Y541000D03*
X689500Y532100D03*
G54D52*
X151400Y54700D03*
X116689Y54714D03*
X103528D03*
X151400Y66300D03*
X116689Y66314D03*
X103528D03*
X164500Y54700D03*
Y66300D03*
G54D71*
X166649Y135247D03*
G54D26*
X70675Y134665D03*
X54925D03*
X70675Y155935D03*
X54925D03*
G54D53*
X134000Y52600D03*
Y77400D03*
X281963Y485753D03*
Y510553D03*
X340774Y65179D03*
Y40379D03*
X310274Y65179D03*
Y40379D03*
X343791Y395598D03*
X343292Y485604D03*
X312767Y485379D03*
X343791Y420398D03*
X323221Y445562D03*
Y470362D03*
X343292Y510404D03*
X312767Y510179D03*
X371274Y65179D03*
Y40379D03*
G54D17*
X58059Y84803D03*
Y86768D03*
Y88738D03*
Y90708D03*
Y92673D03*
X74359D03*
Y90708D03*
Y88738D03*
Y86768D03*
Y84803D03*
X107899Y197156D03*
Y195191D03*
Y193221D03*
Y191251D03*
Y189286D03*
X91599D03*
Y191251D03*
Y193221D03*
Y195191D03*
Y197156D03*
X82163Y244428D03*
Y246398D03*
Y248368D03*
Y250338D03*
Y252308D03*
Y254278D03*
Y256248D03*
Y258218D03*
Y260188D03*
Y262158D03*
Y264128D03*
Y266098D03*
Y268068D03*
Y270038D03*
Y272008D03*
Y273978D03*
Y275948D03*
Y277918D03*
Y279888D03*
Y281858D03*
Y283828D03*
Y285798D03*
Y287768D03*
Y289738D03*
X157763Y273978D03*
Y272008D03*
Y270038D03*
Y268068D03*
Y266098D03*
Y264128D03*
Y262158D03*
Y260188D03*
Y258218D03*
Y256248D03*
Y254278D03*
Y252308D03*
Y250338D03*
Y248368D03*
Y246398D03*
Y244428D03*
Y289738D03*
Y287768D03*
Y285798D03*
Y283828D03*
Y281858D03*
Y279888D03*
Y277918D03*
Y275948D03*
X476320Y508067D03*
Y506102D03*
Y504132D03*
Y502162D03*
Y500197D03*
X460020D03*
Y502162D03*
Y504132D03*
Y506102D03*
Y508067D03*
G54D80*
X234222Y399876D03*
Y396136D03*
Y392396D03*
X243222D03*
Y399876D03*
G54D62*
X147553Y327542D03*
X143853Y327642D03*
X136317Y331756D03*
X132717D03*
X124973Y327655D03*
X121255Y327729D03*
X201315Y81433D03*
X154641Y154448D03*
X191557Y344189D03*
X188047Y344249D03*
X180438Y340053D03*
X176898Y340013D03*
X169385Y335813D03*
X165885D03*
X158445Y331748D03*
X154845Y331848D03*
X185315Y410533D03*
X213780Y352494D03*
X210180D03*
X202638Y348349D03*
X199138D03*
X206788Y420845D03*
X207834Y465396D03*
X221100Y134300D03*
X249515Y394680D03*
X224885Y359814D03*
X221424Y359867D03*
X256700Y489500D03*
X260200D03*
X353898Y467743D03*
X349945Y467753D03*
X358012Y467743D03*
X345813D03*
X394125Y398023D03*
X390405D03*
X383048D03*
X379164D03*
X397699D03*
X386726D03*
X375610D03*
X365427Y467743D03*
X361642D03*
X451123Y503983D03*
X504316Y397727D03*
X664700Y543300D03*
G54D35*
X53547Y322486D03*
Y302486D03*
X182681Y580832D03*
Y560832D03*
G54D44*
X30494Y493063D03*
X83288Y184954D03*
X162913Y171759D03*
X155231Y176850D03*
X213782Y427789D03*
X216943Y418666D03*
X250300Y461100D03*
X241356Y478217D03*
X242273Y468923D03*
X304774Y475788D03*
X300300Y462500D03*
X304813Y471007D03*
G54D18*
X43100Y103500D03*
X46863Y378983D03*
X65763Y370883D03*
X59384Y637701D03*
X84296Y192448D03*
X149031Y168900D03*
X115096Y186970D03*
X79922Y632686D03*
X80191Y647887D03*
X80653Y747704D03*
X80464Y764806D03*
X217113Y130860D03*
X172685Y172033D03*
X168353Y140290D03*
X189415Y413533D03*
X185266Y481943D03*
X225231Y61620D03*
X225002Y130816D03*
X231350Y214208D03*
X226428Y395041D03*
X222254Y394949D03*
X236637Y383693D03*
X241728Y364256D03*
X237455Y375355D03*
X246800Y436600D03*
X231108Y464137D03*
X226992Y464083D03*
X537200Y394400D03*
X657609Y470923D03*
X661709Y466823D03*
X674109Y454523D03*
X678509Y450323D03*
X654800Y529500D03*
X736209Y475223D03*
X740309Y479423D03*
X723809Y462723D03*
X719709Y458623D03*
G54D54*
X97645Y134201D03*
X92645D03*
X87645D03*
X82645D03*
Y114201D03*
X87645D03*
X92645D03*
X97645D03*
G54D81*
X268768Y415628D03*
Y430628D03*
G54D90*
X702989Y515755D03*
X691989D03*
X703000Y524500D03*
X692000D03*
G54D72*
X217108Y145568D03*
Y163568D03*
G54D63*
X147553Y323942D03*
X143853Y324042D03*
X136317Y328156D03*
X132717D03*
X124973Y324055D03*
X121255Y324129D03*
X201315Y77833D03*
X154641Y150848D03*
X202638Y344749D03*
X199138D03*
X191557Y340589D03*
X188047Y340649D03*
X180438Y336453D03*
X176898Y336413D03*
X169385Y332213D03*
X165885D03*
X158445Y328148D03*
X154845Y328248D03*
X185315Y406933D03*
X213780Y348894D03*
X210180D03*
X206788Y417245D03*
X207834Y461796D03*
X221100Y130700D03*
X249515Y391080D03*
X224885Y356214D03*
X221424Y356267D03*
X256700Y485900D03*
X260200D03*
X353898Y464143D03*
X349945Y464153D03*
X358012Y464143D03*
X345813D03*
X394125Y394423D03*
X390405D03*
X383048D03*
X379164D03*
X397699D03*
X386726D03*
X375610D03*
X365427Y464143D03*
X361642D03*
X451123Y500383D03*
X504316Y394127D03*
X664700Y539700D03*
G54D27*
X71800Y100400D03*
X58800Y101600D03*
X68200Y218900D03*
X21515Y378719D03*
X34015Y379038D03*
X40915Y389933D03*
X27515Y413492D03*
X50900Y369500D03*
X55500Y383100D03*
X40715Y382433D03*
X57900Y372700D03*
X40381Y472477D03*
X43015Y453102D03*
X23662Y429056D03*
X10515Y436844D03*
X52215Y422661D03*
X11803Y444233D03*
X21015Y440028D03*
X27293Y435619D03*
X45815Y461517D03*
X25415Y449205D03*
X51515Y479433D03*
X17228Y453864D03*
X47315Y469617D03*
X110000Y90700D03*
X130415Y168033D03*
X148715Y158433D03*
X84600Y199700D03*
X87100Y209300D03*
X95100Y215200D03*
X109100Y214300D03*
X130000Y228000D03*
X128918Y307533D03*
X209800Y88600D03*
X217909Y110100D03*
X183900Y150600D03*
X215700Y181620D03*
X154800Y145800D03*
X181200Y176300D03*
X180015Y202933D03*
X169800Y155796D03*
X165162Y155909D03*
X169709Y160049D03*
X165388Y160094D03*
X163979Y141189D03*
X202300Y181000D03*
X170315Y291733D03*
X200315Y400633D03*
X189700Y403800D03*
X210600Y423000D03*
X181300Y463300D03*
X204700Y441000D03*
X181300Y417800D03*
X215100Y453900D03*
X207200Y447100D03*
X186515Y498933D03*
X202715Y501618D03*
X217015Y737933D03*
X213415Y748233D03*
X283615Y59733D03*
X285615Y52233D03*
X285015Y42433D03*
X232615Y106010D03*
X225919Y88394D03*
X225937Y80731D03*
X221710Y80767D03*
X221722Y88431D03*
X230158Y88359D03*
X230123Y80805D03*
X225851Y73774D03*
X221740Y73844D03*
X229870Y73970D03*
X229400Y134000D03*
X242800Y93300D03*
X238771Y101724D03*
X235700Y204940D03*
X227900Y180500D03*
X227116Y223400D03*
X290215Y269533D03*
X253700Y393900D03*
X245100Y386300D03*
X248900Y407500D03*
X224403Y405302D03*
X245000Y380700D03*
X257800Y428100D03*
X222900Y463100D03*
X224800Y471600D03*
X248410Y466092D03*
X233700Y487100D03*
X242900Y483600D03*
X228000Y478400D03*
X242900Y473600D03*
X238000Y422100D03*
X227400D03*
X232750Y422200D03*
X243900Y424500D03*
X250800Y436300D03*
X227915Y503233D03*
X228415Y539233D03*
X225215Y512533D03*
X229715Y747933D03*
X226015Y737933D03*
X230515Y793233D03*
X240615Y782733D03*
X240715Y771333D03*
X327515Y185333D03*
X297915Y135484D03*
X291500Y473900D03*
X378715Y162033D03*
X430515Y395333D03*
X394815Y420433D03*
X372815Y474033D03*
X416215Y512533D03*
X392315Y667333D03*
X409415Y735333D03*
X395515Y883833D03*
X437915Y63033D03*
X484915Y271133D03*
X499500Y405382D03*
X460591Y484133D03*
X478515D03*
X486700Y485900D03*
X500000Y416969D03*
X483200Y512828D03*
X483402Y507800D03*
X464300Y519000D03*
X490900Y524700D03*
X491300Y553900D03*
X442600Y503892D03*
X477115Y563733D03*
X462315Y791333D03*
X554515Y180233D03*
X537842Y407738D03*
X537500Y401600D03*
X529200Y388900D03*
X508500Y393600D03*
X506000Y486293D03*
X511015Y431233D03*
X525338Y523500D03*
X529800Y542200D03*
X525800Y535900D03*
X542615Y676933D03*
X621115Y55033D03*
X575015Y264733D03*
X641400Y394600D03*
X640200Y536400D03*
X575315Y730733D03*
X586415Y786233D03*
X577315Y881833D03*
X653500Y394600D03*
X702000Y485700D03*
X688615Y485133D03*
X650700Y536600D03*
X660800Y539800D03*
X682015Y493633D03*
X668135Y523360D03*
X672161Y528021D03*
X676550Y523677D03*
X672342Y519560D03*
X672257Y523769D03*
X691200Y507800D03*
X644415Y560714D03*
X687315Y762233D03*
X685707Y778945D03*
X685215Y823933D03*
X685108Y855661D03*
X727515Y179133D03*
X746715Y331203D03*
X747915Y541533D03*
X763510Y518353D03*
X758641Y524059D03*
X761015Y503960D03*
X754800Y546300D03*
X742400Y532597D03*
X741600Y541600D03*
X736000Y539500D03*
X738627Y545621D03*
X746951Y525677D03*
X752515Y514433D03*
X760911Y539742D03*
X759100Y489500D03*
X761000Y552844D03*
X757000Y555900D03*
X742300Y569500D03*
X760515Y560714D03*
X737062Y845433D03*
G54D45*
X54724Y557087D03*
Y620079D03*
Y675197D03*
Y738189D03*
X144843Y798779D03*
Y874449D03*
G54D36*
G01X-771361Y-182763D02*
Y-262763D01*
G01Y-218263D02*
X373639D01*
G01X-771361Y-262763D02*
X373639D01*
G01X-775361Y-166763D02*
G02I-12000J0D01*
G01X-780511D02*
G02I-6850J0D01*
G01X-787361Y-182763D02*
Y-150763D01*
G01X-771361Y-166763D02*
X-803361D01*
G01X-771361Y-182763D02*
X373639D01*
G01X-413861D02*
Y-262763D01*
G01X-276361Y-182763D02*
Y-262763D01*
G01X-161361Y-182763D02*
Y-262763D01*
G01X6139Y-182763D02*
Y-262763D01*
G01X176139Y-182763D02*
Y-262763D01*
G01X373639Y-182763D02*
Y-262763D01*
G01X401639Y-166763D02*
G02I-12000J0D01*
G01X396489D02*
G02I-6850J0D01*
G01X389639Y-182763D02*
Y-150763D01*
G01X405639Y-166763D02*
X373639D01*
X72838Y388509D03*
X68901D03*
X72838Y392446D03*
X68901D03*
X64964D03*
X72838Y396383D03*
X68901D03*
X64964D03*
X68901Y486935D03*
Y494809D03*
X72838D03*
X64964Y490872D03*
X68901D03*
X72838D03*
X64964Y486935D03*
X72838D03*
X167327Y388509D03*
X163390D03*
X171264Y392446D03*
X167327D03*
X163390D03*
X171264Y396383D03*
X167327D03*
X163390D03*
X171264Y486935D03*
X167327D03*
X163390D03*
X171264Y490872D03*
X167327D03*
X163390D03*
X167327Y494809D03*
X163390D03*
G54D19*
X43100Y106900D03*
X46863Y382383D03*
X65763Y374283D03*
X59384Y641101D03*
X84296Y195848D03*
X149031Y172300D03*
X115096Y190370D03*
X79922Y636086D03*
X80191Y651287D03*
X80653Y751104D03*
X80464Y768206D03*
X217113Y134260D03*
X172685Y175433D03*
X168353Y143690D03*
X185266Y485343D03*
X189415Y416933D03*
X225231Y65020D03*
X225002Y134216D03*
X231350Y217608D03*
X226428Y398441D03*
X222254Y398349D03*
X236637Y387093D03*
X241728Y367656D03*
X237455Y378755D03*
X246800Y440000D03*
X231108Y467537D03*
X226992Y467483D03*
X537200Y397800D03*
X657609Y474323D03*
X661709Y470223D03*
X674109Y457923D03*
X678509Y453723D03*
X654800Y532900D03*
X736209Y478623D03*
X740309Y482823D03*
X723809Y466123D03*
X719709Y462023D03*
G54D28*
X77200Y199800D03*
X24390Y497166D03*
X95441Y203600D03*
X215461Y461171D03*
X215434Y464704D03*
X229600Y454700D03*
X294900Y466600D03*
X475128Y493916D03*
X456920Y493874D03*
G54D73*
X200788Y473418D03*
X216324D03*
X200788Y493918D03*
X216324D03*
G54D55*
X151866Y100449D03*
X189416D03*
G54D46*
X75118Y561024D03*
Y564174D03*
Y567323D03*
Y570473D03*
Y573622D03*
Y576772D03*
Y579922D03*
Y583071D03*
Y586221D03*
Y589370D03*
Y592520D03*
Y595670D03*
Y598819D03*
Y601969D03*
Y605118D03*
Y608268D03*
Y611418D03*
Y614567D03*
Y679134D03*
Y682284D03*
Y685433D03*
Y688583D03*
Y691732D03*
Y694882D03*
Y698032D03*
Y701181D03*
Y704331D03*
Y707480D03*
Y710630D03*
Y713780D03*
Y716929D03*
Y720079D03*
Y723228D03*
Y726378D03*
Y729528D03*
Y732677D03*
X85000Y562599D03*
Y565748D03*
Y568898D03*
Y572048D03*
Y575197D03*
Y578347D03*
Y581496D03*
Y584646D03*
Y587796D03*
Y590945D03*
Y594095D03*
Y597244D03*
Y600394D03*
Y603544D03*
Y606693D03*
Y609843D03*
Y612992D03*
Y616142D03*
Y680709D03*
Y683858D03*
Y687008D03*
Y690158D03*
Y693307D03*
Y696457D03*
Y699606D03*
Y702756D03*
Y705906D03*
Y709055D03*
Y712205D03*
Y715354D03*
Y718504D03*
Y721654D03*
Y724803D03*
Y727953D03*
Y731102D03*
Y734252D03*
X175118Y818504D03*
Y821654D03*
Y824804D03*
Y827954D03*
Y831104D03*
Y834254D03*
Y837399D03*
X165238Y816929D03*
Y820079D03*
Y823229D03*
Y826379D03*
Y829529D03*
Y832679D03*
Y835829D03*
X175118Y840549D03*
X165238Y838974D03*
Y842124D03*
X175118Y843699D03*
Y846849D03*
Y849999D03*
Y853149D03*
Y856299D03*
X165238Y845274D03*
Y848424D03*
Y851574D03*
Y854724D03*
G54D37*
X64964Y416068D03*
X68901D03*
X72838D03*
X76775D03*
X64964Y412131D03*
X68901D03*
X72838D03*
X76775D03*
X64964Y408194D03*
X68901D03*
X72838D03*
X76775D03*
X64964Y404257D03*
X68901D03*
X72838D03*
X76775D03*
X64964Y400320D03*
X68901D03*
X72838D03*
X76775D03*
Y396383D03*
Y392446D03*
Y388509D03*
X64964Y482998D03*
X68901D03*
X72838D03*
X76775D03*
X64964Y479061D03*
X68901D03*
X72838D03*
X76775D03*
X64964Y475124D03*
X68901D03*
X72838D03*
X76775D03*
X64964Y471187D03*
X68901D03*
X72838D03*
X76775D03*
X64964Y467250D03*
X68901D03*
X72838D03*
X76775D03*
X64964Y463313D03*
X68901D03*
X72838D03*
X76775D03*
X64964Y459376D03*
X68901D03*
X72838D03*
X76775D03*
X64964Y455439D03*
X68901D03*
X72838D03*
X76775D03*
X64964Y451502D03*
X68901D03*
X72838D03*
X76775D03*
X64964Y447565D03*
X68901D03*
X72838D03*
X76775D03*
X64964Y443628D03*
X68901D03*
X72838D03*
X76775D03*
X64964Y439690D03*
X68901D03*
X72838D03*
X76775D03*
X64964Y435753D03*
X68901D03*
X72838D03*
X76775D03*
X64964Y431816D03*
X68901D03*
X72838D03*
X76775D03*
X64964Y427879D03*
X68901D03*
X72838D03*
X76775D03*
X64964Y423942D03*
X68901D03*
X72838D03*
X76775D03*
X64964Y420005D03*
X68901D03*
X72838D03*
X76775D03*
Y494809D03*
Y490872D03*
Y486935D03*
X80712Y416068D03*
X84649D03*
X88586D03*
X92523D03*
X96460D03*
X100397D03*
X104334D03*
X108271D03*
X112208D03*
X116145D03*
X120083D03*
X124020D03*
X127957D03*
X131894D03*
X135831D03*
X139768D03*
X143705D03*
X147642D03*
X80712Y412131D03*
X84649D03*
X88586D03*
X92523D03*
X96460D03*
X100397D03*
X104334D03*
X108271D03*
X112208D03*
X116145D03*
X120083D03*
X124020D03*
X127957D03*
X131894D03*
X135831D03*
X139768D03*
X143705D03*
X147642D03*
X80712Y408194D03*
X84649D03*
X88586D03*
X92523D03*
X96460D03*
X100397D03*
X104334D03*
X108271D03*
X112208D03*
X116145D03*
X120083D03*
X124020D03*
X127957D03*
X131894D03*
X135831D03*
X139768D03*
X143705D03*
X147642D03*
X80712Y404257D03*
X84649D03*
X88586D03*
X92523D03*
X96460D03*
X100397D03*
X104334D03*
X108271D03*
X112208D03*
X116145D03*
X120083D03*
X124020D03*
X127957D03*
X131894D03*
X135831D03*
X139768D03*
X143705D03*
X147642D03*
X80712Y400320D03*
X84649D03*
X88586D03*
X92523D03*
X96460D03*
X100397D03*
X104334D03*
X108271D03*
X112208D03*
X116145D03*
X120083D03*
X124020D03*
X127957D03*
X131894D03*
X135831D03*
X139768D03*
X143705D03*
X147642D03*
X80712Y396383D03*
X84649D03*
X88586D03*
X92523D03*
X96460D03*
X100397D03*
X104334D03*
X108271D03*
X112208D03*
X116145D03*
X120083D03*
X124020D03*
X127957D03*
X131894D03*
X135831D03*
X139768D03*
X143705D03*
X147642D03*
X80712Y392446D03*
X84649D03*
X88586D03*
X92523D03*
X96460D03*
X100397D03*
X104334D03*
X108271D03*
X112208D03*
X116145D03*
X120083D03*
X124020D03*
X127957D03*
X131894D03*
X135831D03*
X139768D03*
X143705D03*
X147642D03*
X80712Y388509D03*
X84649D03*
X88586D03*
X92523D03*
X96460D03*
X100397D03*
X104334D03*
X108271D03*
X112208D03*
X116145D03*
X120083D03*
X124020D03*
X127957D03*
X131894D03*
X135831D03*
X139768D03*
X143705D03*
X147642D03*
X80712Y482998D03*
X84649D03*
X88586D03*
X92523D03*
X96460D03*
X100397D03*
X104334D03*
X108271D03*
X112208D03*
X116145D03*
X120083D03*
X124020D03*
X127957D03*
X131894D03*
X135831D03*
X139768D03*
X143705D03*
X147642D03*
X80712Y479061D03*
X84649D03*
X88586D03*
X92523D03*
X96460D03*
X100397D03*
X104334D03*
X108271D03*
X112208D03*
X116145D03*
X120083D03*
X124020D03*
X127957D03*
X131894D03*
X135831D03*
X139768D03*
X143705D03*
X147642D03*
X80712Y475124D03*
X84649D03*
X88586D03*
X92523D03*
X96460D03*
X100397D03*
X104334D03*
X108271D03*
X112208D03*
X116145D03*
X120083D03*
X124020D03*
X127957D03*
X131894D03*
X135831D03*
X139768D03*
X143705D03*
X147642D03*
X80712Y471187D03*
X84649D03*
X88586D03*
X92523D03*
X96460D03*
X100397D03*
X104334D03*
X108271D03*
X112208D03*
X116145D03*
X120083D03*
X124020D03*
X127957D03*
X131894D03*
X135831D03*
X139768D03*
X143705D03*
X147642D03*
X80712Y467250D03*
X84649D03*
X88586D03*
X92523D03*
X96460D03*
X100397D03*
X104334D03*
X108271D03*
X112208D03*
X116145D03*
X120083D03*
X124020D03*
X127957D03*
X131894D03*
X135831D03*
X139768D03*
X143705D03*
X147642D03*
X80712Y463313D03*
X84649D03*
X88586D03*
X92523D03*
X96460D03*
X100397D03*
X104334D03*
X108271D03*
X112208D03*
X116145D03*
X120083D03*
X124020D03*
X127957D03*
X131894D03*
X135831D03*
X139768D03*
X143705D03*
X147642D03*
X80712Y459376D03*
X84649D03*
X88586D03*
X92523D03*
X96460D03*
X100397D03*
X104334D03*
X108271D03*
X112208D03*
X116145D03*
X120083D03*
X124020D03*
X127957D03*
X131894D03*
X135831D03*
X139768D03*
X143705D03*
X147642D03*
X80712Y455439D03*
X84649D03*
X88586D03*
X92523D03*
X96460D03*
X100397D03*
X104334D03*
X108271D03*
X112208D03*
X116145D03*
X120083D03*
X124020D03*
X127957D03*
X131894D03*
X135831D03*
X139768D03*
X143705D03*
X147642D03*
X80712Y451502D03*
X84649D03*
X88586D03*
X92523D03*
X96460D03*
X100397D03*
X104334D03*
X108271D03*
X112208D03*
X116145D03*
X120083D03*
X124020D03*
X127957D03*
X131894D03*
X135831D03*
X139768D03*
X143705D03*
X147642D03*
X80712Y447565D03*
X84649D03*
X88586D03*
X92523D03*
X96460D03*
X100397D03*
X104334D03*
X108271D03*
X112208D03*
X116145D03*
X120083D03*
X124020D03*
X127957D03*
X131894D03*
X135831D03*
X139768D03*
X143705D03*
X147642D03*
X80712Y443628D03*
X84649D03*
X88586D03*
X92523D03*
X96460D03*
X100397D03*
X104334D03*
X108271D03*
X112208D03*
X116145D03*
X120083D03*
X124020D03*
X127957D03*
X131894D03*
X135831D03*
X139768D03*
X143705D03*
X147642D03*
X80712Y439690D03*
X84649D03*
X88586D03*
X92523D03*
X96460D03*
X100397D03*
X104334D03*
X108271D03*
X112208D03*
X116145D03*
X120083D03*
X124020D03*
X127957D03*
X131894D03*
X135831D03*
X139768D03*
X143705D03*
X147642D03*
X80712Y435753D03*
X84649D03*
X88586D03*
X92523D03*
X96460D03*
X100397D03*
X104334D03*
X108271D03*
X112208D03*
X116145D03*
X120083D03*
X124020D03*
X127957D03*
X131894D03*
X135831D03*
X139768D03*
X143705D03*
X147642D03*
X80712Y431816D03*
X84649D03*
X88586D03*
X92523D03*
X96460D03*
X100397D03*
X104334D03*
X108271D03*
X112208D03*
X116145D03*
X120083D03*
X124020D03*
X127957D03*
X131894D03*
X135831D03*
X139768D03*
X143705D03*
X147642D03*
X80712Y427879D03*
X84649D03*
X88586D03*
X92523D03*
X96460D03*
X100397D03*
X104334D03*
X108271D03*
X112208D03*
X116145D03*
X120083D03*
X124020D03*
X127957D03*
X131894D03*
X135831D03*
X139768D03*
X143705D03*
X147642D03*
X80712Y423942D03*
X84649D03*
X88586D03*
X92523D03*
X96460D03*
X100397D03*
X104334D03*
X108271D03*
X112208D03*
X116145D03*
X120083D03*
X124020D03*
X127957D03*
X131894D03*
X135831D03*
X139768D03*
X143705D03*
X147642D03*
X80712Y420005D03*
X84649D03*
X88586D03*
X92523D03*
X96460D03*
X100397D03*
X104334D03*
X108271D03*
X112208D03*
X116145D03*
X120083D03*
X124020D03*
X127957D03*
X131894D03*
X135831D03*
X139768D03*
X143705D03*
X147642D03*
X80712Y494809D03*
X84649D03*
X88586D03*
X92523D03*
X96460D03*
X100397D03*
X104334D03*
X108271D03*
X112208D03*
X116145D03*
X120083D03*
X124020D03*
X127957D03*
X131894D03*
X135831D03*
X139768D03*
X143705D03*
X147642D03*
X80712Y490872D03*
X84649D03*
X88586D03*
X92523D03*
X96460D03*
X100397D03*
X104334D03*
X108271D03*
X112208D03*
X116145D03*
X120083D03*
X124020D03*
X127957D03*
X131894D03*
X135831D03*
X139768D03*
X143705D03*
X147642D03*
X80712Y486935D03*
X84649D03*
X88586D03*
X92523D03*
X96460D03*
X100397D03*
X104334D03*
X108271D03*
X112208D03*
X116145D03*
X120083D03*
X124020D03*
X127957D03*
X131894D03*
X135831D03*
X139768D03*
X143705D03*
X147642D03*
X163390Y416068D03*
X167327D03*
X171264D03*
X163390Y412131D03*
X167327D03*
X171264D03*
X163390Y408194D03*
X167327D03*
X171264D03*
X163390Y404257D03*
X167327D03*
X171264D03*
X163390Y400320D03*
X167327D03*
X171264D03*
X151579Y416068D03*
X155516D03*
X159453D03*
X151579Y412131D03*
X155516D03*
X159453D03*
X151579Y408194D03*
X155516D03*
X159453D03*
X151579Y404257D03*
X155516D03*
X159453D03*
X151579Y400320D03*
X155516D03*
X159453D03*
X151579Y396383D03*
X155516D03*
X159453D03*
X151579Y392446D03*
X155516D03*
X159453D03*
X151579Y388509D03*
X155516D03*
X159453D03*
X163390Y482998D03*
X167327D03*
X171264D03*
X163390Y479061D03*
X167327D03*
X171264D03*
X163390Y475124D03*
X167327D03*
X171264D03*
X163390Y471187D03*
X167327D03*
X171264D03*
X163390Y467250D03*
X167327D03*
X171264D03*
X163390Y463313D03*
X167327D03*
X171264D03*
X163390Y459376D03*
X167327D03*
X171264D03*
X163390Y455439D03*
X167327D03*
X171264D03*
X163390Y451502D03*
X167327D03*
X171264D03*
X163390Y447565D03*
X167327D03*
X171264D03*
X163390Y443628D03*
X167327D03*
X171264D03*
X163390Y439690D03*
X167327D03*
X171264D03*
X163390Y435753D03*
X167327D03*
X171264D03*
X163390Y431816D03*
X167327D03*
X171264D03*
X163390Y427879D03*
X167327D03*
X171264D03*
X163390Y423942D03*
X167327D03*
X171264D03*
X163390Y420005D03*
X167327D03*
X171264D03*
X151579Y482998D03*
X155516D03*
X159453D03*
X151579Y479061D03*
X155516D03*
X159453D03*
X151579Y475124D03*
X155516D03*
X159453D03*
X151579Y471187D03*
X155516D03*
X159453D03*
X151579Y467250D03*
X155516D03*
X159453D03*
X151579Y463313D03*
X155516D03*
X159453D03*
X151579Y459376D03*
X155516D03*
X159453D03*
X151579Y455439D03*
X155516D03*
X159453D03*
X151579Y451502D03*
X155516D03*
X159453D03*
X151579Y447565D03*
X155516D03*
X159453D03*
X151579Y443628D03*
X155516D03*
X159453D03*
X151579Y439690D03*
X155516D03*
X159453D03*
X151579Y435753D03*
X155516D03*
X159453D03*
X151579Y431816D03*
X155516D03*
X159453D03*
X151579Y427879D03*
X155516D03*
X159453D03*
X151579Y423942D03*
X155516D03*
X159453D03*
X151579Y420005D03*
X155516D03*
X159453D03*
X151579Y494809D03*
X155516D03*
X159453D03*
X151579Y490872D03*
X155516D03*
X159453D03*
X151579Y486935D03*
X155516D03*
X159453D03*
G54D91*
X781514Y330730D03*
Y334665D03*
Y338605D03*
Y342540D03*
Y381910D03*
Y385850D03*
Y389785D03*
Y393720D03*
Y397660D03*
Y401595D03*
Y405535D03*
Y409470D03*
Y413405D03*
Y346480D03*
Y350415D03*
Y354350D03*
Y358290D03*
Y362225D03*
Y366165D03*
Y370100D03*
Y417345D03*
Y421280D03*
Y425220D03*
Y429155D03*
Y433090D03*
Y437030D03*
Y440965D03*
Y444905D03*
Y448840D03*
Y452775D03*
Y456715D03*
Y460650D03*
Y464590D03*
Y468525D03*
Y472460D03*
Y476400D03*
Y480335D03*
Y484275D03*
Y488210D03*
Y492145D03*
Y496085D03*
Y500020D03*
Y503960D03*
Y507895D03*
Y511830D03*
Y515770D03*
Y519705D03*
Y523645D03*
Y527580D03*
Y531515D03*
Y535455D03*
Y539390D03*
Y543330D03*
Y547265D03*
Y551200D03*
Y555140D03*
Y559075D03*
Y563015D03*
Y566950D03*
Y570885D03*
Y574825D03*
Y578760D03*
Y582700D03*
Y586635D03*
Y590575D03*
Y594510D03*
Y598445D03*
Y602385D03*
Y606320D03*
Y610260D03*
Y614195D03*
Y618130D03*
Y622070D03*
Y626005D03*
Y629945D03*
Y633880D03*
Y637815D03*
Y641755D03*
Y645690D03*
Y649630D03*
Y657500D03*
Y740179D03*
Y744114D03*
Y748054D03*
Y751989D03*
Y755929D03*
Y759864D03*
Y763799D03*
Y767739D03*
Y779549D03*
Y771674D03*
Y775614D03*
Y791359D03*
Y795299D03*
Y799234D03*
Y803169D03*
Y807109D03*
Y814984D03*
G54D64*
X144843Y812994D03*
Y860234D03*
X286982Y828335D03*
X276982D03*
X286982Y818335D03*
X276982D03*
X356982Y828335D03*
X346982D03*
X336982D03*
X326982D03*
X316982D03*
X306982D03*
X296982D03*
X356982Y818335D03*
X346982D03*
X336982D03*
X326982D03*
X316982D03*
X306982D03*
X296982D03*
X366982Y828335D03*
Y818335D03*
G54D82*
X501750Y380000D03*
X520250D03*
G54D74*
X216324Y483668D03*
X200788D03*
G54D38*
X43000Y354200D03*
X245200Y551000D03*
G54D65*
X216447Y72290D03*
Y74259D03*
Y76227D03*
Y78196D03*
Y80164D03*
Y82133D03*
Y84102D03*
Y86070D03*
Y88039D03*
Y90007D03*
Y91976D03*
X235733D03*
Y90007D03*
Y88039D03*
Y86070D03*
Y84102D03*
Y82133D03*
Y80164D03*
Y78196D03*
Y76227D03*
Y74259D03*
Y72290D03*
G54D83*
X497166Y535119D03*
Y537679D03*
Y540239D03*
Y542799D03*
X519366D03*
Y540239D03*
Y537679D03*
Y535119D03*
X695412Y836919D03*
Y834419D03*
Y831919D03*
Y829419D03*
Y826919D03*
X696098Y796516D03*
Y794016D03*
Y791516D03*
Y789016D03*
Y786516D03*
Y784016D03*
Y781516D03*
Y779016D03*
Y776516D03*
Y774016D03*
Y771516D03*
Y769016D03*
X695412Y854419D03*
Y851919D03*
Y849419D03*
Y846919D03*
Y844419D03*
Y841919D03*
Y839419D03*
X716012Y826919D03*
Y829419D03*
Y831919D03*
Y834419D03*
Y836919D03*
X716698Y769016D03*
Y771516D03*
Y774016D03*
Y776516D03*
Y779016D03*
Y781516D03*
Y784016D03*
Y786516D03*
Y789016D03*
Y791516D03*
Y794016D03*
Y796516D03*
X716012Y839419D03*
Y841919D03*
Y844419D03*
Y846919D03*
Y849419D03*
Y851919D03*
Y854419D03*
G54D29*
X43760Y172352D03*
X69800Y180800D03*
X103041Y203500D03*
X115041Y202800D03*
X144600Y233900D03*
X214190Y98033D03*
X199561Y113456D03*
X189163Y240983D03*
X189121Y244556D03*
X189163Y248183D03*
Y237383D03*
X185309Y421839D03*
X189466Y493343D03*
X249782Y399333D03*
X249041Y383206D03*
X241555Y375055D03*
X241530Y371576D03*
X245865Y363969D03*
X245828Y360456D03*
X237500Y454700D03*
X223399Y778667D03*
X487203Y501502D03*
X487218Y494161D03*
X487223Y497927D03*
X515916Y424009D03*
X517452Y552477D03*
X517613Y548807D03*
X693339Y759399D03*
X693392Y762972D03*
X694427Y817304D03*
X694375Y820842D03*
G54D47*
X68140Y665912D03*
X104541Y207700D03*
X250667Y69296D03*
X277770Y794774D03*
X532500Y397400D03*
G54D56*
X139878Y135201D03*
Y150469D03*
G54D92*
X779564Y653565D03*
Y811044D03*
G54D93*
G01X-755164Y-252763D02*
Y-235263D01*
G01X-746868D02*
X-755164Y-246055D01*
G01X-745558Y-252763D02*
X-751453Y-241097D01*
G01X-737883Y-252763D02*
Y-235263D01*
X-727839Y-252763D01*
Y-235263D01*
G01X-715361Y-252763D02*
X-717108Y-252471D01*
X-718636Y-251305D01*
X-719946Y-249555D01*
X-720820Y-247513D01*
X-721256Y-245180D01*
Y-242846D01*
X-720820Y-240513D01*
X-719946Y-238471D01*
X-718636Y-236722D01*
X-717108Y-235555D01*
X-715361Y-235263D01*
X-713615Y-235555D01*
X-712086Y-236722D01*
X-710776Y-238471D01*
X-709902Y-240513D01*
X-709466Y-242846D01*
Y-245180D01*
X-709902Y-247513D01*
X-710776Y-249555D01*
X-712086Y-251305D01*
X-713615Y-252471D01*
X-715361Y-252763D01*
G01X-702446D02*
X-693276Y-235263D01*
G01X-702446D02*
X-693276Y-252763D01*
G01X-658494D02*
X-667228D01*
Y-235263D01*
X-658494D01*
G01X-661988Y-243721D02*
X-667228D01*
G01X-649946Y-252763D02*
X-640776Y-235263D01*
G01X-649946D02*
X-640776Y-252763D01*
G01X-632228D02*
Y-235263D01*
X-626988D01*
X-625241Y-236138D01*
X-623931Y-238180D01*
X-623494Y-240513D01*
X-623931Y-242846D01*
X-625023Y-244596D01*
X-626988Y-245472D01*
X-632228D01*
G01X-615820Y-252763D02*
X-610361Y-235263D01*
X-604902Y-252763D01*
G01X-606868Y-246638D02*
X-613855D01*
G01X-597883Y-252763D02*
Y-235263D01*
X-587839Y-252763D01*
Y-235263D01*
G01X-580164Y-252763D02*
Y-235263D01*
X-575798D01*
X-574051Y-236138D01*
X-572741Y-237305D01*
X-571649Y-239054D01*
X-570776Y-241097D01*
X-570558Y-244013D01*
X-570776Y-246930D01*
X-571649Y-248972D01*
X-572741Y-250722D01*
X-574051Y-251888D01*
X-575798Y-252763D01*
X-580164D01*
G01X-553494D02*
X-562228D01*
Y-235263D01*
X-553494D01*
G01X-556988Y-243721D02*
X-562228D01*
G01X-544728Y-252763D02*
Y-235263D01*
X-539269D01*
X-537523Y-236138D01*
X-536431Y-237305D01*
X-535994Y-239638D01*
X-536431Y-241972D01*
X-537741Y-243430D01*
X-539269Y-244305D01*
X-544728D01*
G01X-539269D02*
X-535994Y-252763D01*
G01X-503615Y-243430D02*
X-502741Y-242555D01*
X-502086Y-241097D01*
X-501649Y-239054D01*
X-502086Y-237305D01*
X-502959Y-236138D01*
X-504488Y-235263D01*
X-510383D01*
Y-252763D01*
X-503178D01*
X-501649Y-251597D01*
X-500776Y-249846D01*
X-500339Y-247805D01*
X-500776Y-245763D01*
X-502086Y-244013D01*
X-503615Y-243430D01*
X-510383D01*
G01X-487861Y-252763D02*
X-489608Y-252471D01*
X-491136Y-251305D01*
X-492446Y-249555D01*
X-493320Y-247513D01*
X-493756Y-245180D01*
Y-242846D01*
X-493320Y-240513D01*
X-492446Y-238471D01*
X-491136Y-236722D01*
X-489608Y-235555D01*
X-487861Y-235263D01*
X-486115Y-235555D01*
X-484586Y-236722D01*
X-483276Y-238471D01*
X-482402Y-240513D01*
X-481966Y-242846D01*
Y-245180D01*
X-482402Y-247513D01*
X-483276Y-249555D01*
X-484586Y-251305D01*
X-486115Y-252471D01*
X-487861Y-252763D01*
G01X-475820D02*
X-470361Y-235263D01*
X-464902Y-252763D01*
G01X-466868Y-246638D02*
X-473855D01*
G01X-457228Y-252763D02*
Y-235263D01*
X-451769D01*
X-450023Y-236138D01*
X-448931Y-237305D01*
X-448494Y-239638D01*
X-448931Y-241972D01*
X-450241Y-243430D01*
X-451769Y-244305D01*
X-457228D01*
G01X-451769D02*
X-448494Y-252763D01*
G01X-440164D02*
Y-235263D01*
X-435798D01*
X-434051Y-236138D01*
X-432741Y-237305D01*
X-431649Y-239054D01*
X-430776Y-241097D01*
X-430558Y-244013D01*
X-430776Y-246930D01*
X-431649Y-248972D01*
X-432741Y-250722D01*
X-434051Y-251888D01*
X-435798Y-252763D01*
X-440164D01*
G01X-633538Y-207763D02*
Y-190263D01*
X-627861Y-204846D01*
X-622184Y-190263D01*
Y-207763D01*
G01X-610361D02*
X-611671Y-207471D01*
X-612981Y-206305D01*
X-613855Y-204263D01*
X-614291Y-201930D01*
X-613855Y-199596D01*
X-612981Y-197555D01*
X-611671Y-196388D01*
X-610361Y-196097D01*
X-609051Y-196388D01*
X-607741Y-197555D01*
X-606868Y-199596D01*
X-606649Y-201930D01*
X-606868Y-204263D01*
X-607741Y-206305D01*
X-609051Y-207471D01*
X-610361Y-207763D01*
G01X-588931Y-190263D02*
Y-207763D01*
G01Y-205139D02*
X-589804Y-206597D01*
X-591115Y-207471D01*
X-592643Y-207763D01*
X-594389Y-207180D01*
X-595699Y-205722D01*
X-596573Y-203972D01*
X-596791Y-201930D01*
X-596573Y-199888D01*
X-595699Y-198138D01*
X-594389Y-196680D01*
X-592643Y-196097D01*
X-591115Y-196388D01*
X-590023Y-196972D01*
X-588931Y-198138D01*
G01X-578636Y-199888D02*
X-571649D01*
X-572304Y-197846D01*
X-573396Y-196680D01*
X-574924Y-196097D01*
X-576453Y-196388D01*
X-577763Y-197263D01*
X-578636Y-199305D01*
X-579073Y-201055D01*
Y-202805D01*
X-578636Y-204555D01*
X-577544Y-206305D01*
X-576234Y-207471D01*
X-574706Y-207763D01*
X-573178Y-207180D01*
X-571649Y-205430D01*
G01X-557861Y-207763D02*
Y-190263D01*
G01X-380161Y-252763D02*
Y-235263D01*
X-382781Y-238763D01*
G01Y-252763D02*
X-377541D01*
G01X-366809Y-238180D02*
X-365499Y-236430D01*
X-363971Y-235555D01*
X-362224Y-235263D01*
X-360041Y-235846D01*
X-358513Y-237305D01*
X-358076Y-239054D01*
X-358294Y-240805D01*
X-359168Y-242263D01*
X-363534Y-245180D01*
X-365499Y-247221D01*
X-366809Y-250139D01*
X-367246Y-252763D01*
X-358076D01*
G01X-345161Y-235263D02*
X-346908Y-235846D01*
X-348218Y-237305D01*
X-349091Y-239054D01*
X-349746Y-241388D01*
X-349964Y-244013D01*
X-349746Y-246638D01*
X-349091Y-248972D01*
X-348218Y-250722D01*
X-346908Y-252180D01*
X-345161Y-252763D01*
X-343415Y-252180D01*
X-342104Y-250722D01*
X-341231Y-248972D01*
X-340576Y-246638D01*
X-340358Y-244013D01*
X-340576Y-241388D01*
X-341231Y-239054D01*
X-342104Y-237305D01*
X-343415Y-235846D01*
X-345161Y-235263D01*
G01X-327661D02*
X-329408Y-235846D01*
X-330718Y-237305D01*
X-331591Y-239054D01*
X-332246Y-241388D01*
X-332464Y-244013D01*
X-332246Y-246638D01*
X-331591Y-248972D01*
X-330718Y-250722D01*
X-329408Y-252180D01*
X-327661Y-252763D01*
X-325915Y-252180D01*
X-324604Y-250722D01*
X-323731Y-248972D01*
X-323076Y-246638D01*
X-322858Y-244013D01*
X-323076Y-241388D01*
X-323731Y-239054D01*
X-324604Y-237305D01*
X-325915Y-235846D01*
X-327661Y-235263D01*
G01X-307541Y-252763D02*
Y-235263D01*
X-315620Y-247805D01*
X-304702D01*
G01X-393278Y-207763D02*
Y-190263D01*
X-388038D01*
X-386291Y-191138D01*
X-384981Y-193180D01*
X-384544Y-195513D01*
X-384981Y-197846D01*
X-386073Y-199596D01*
X-388038Y-200472D01*
X-393278D01*
G01X-366608Y-191722D02*
X-367918Y-190846D01*
X-369446Y-190263D01*
X-371193D01*
X-373158Y-191138D01*
X-374686Y-192596D01*
X-375778Y-194347D01*
X-376651Y-197263D01*
X-376870Y-199888D01*
X-376433Y-202513D01*
X-375778Y-204263D01*
X-374468Y-206013D01*
X-372939Y-207180D01*
X-371411Y-207763D01*
X-369883D01*
X-368354Y-207180D01*
X-367044Y-206305D01*
X-365952Y-205139D01*
G01X-352165Y-198430D02*
X-351291Y-197555D01*
X-350636Y-196097D01*
X-350199Y-194054D01*
X-350636Y-192305D01*
X-351509Y-191138D01*
X-353038Y-190263D01*
X-358933D01*
Y-207763D01*
X-351728D01*
X-350199Y-206597D01*
X-349326Y-204846D01*
X-348889Y-202805D01*
X-349326Y-200763D01*
X-350636Y-199013D01*
X-352165Y-198430D01*
X-358933D01*
G01X-342961Y-213596D02*
X-329861D01*
G01X-323933Y-207763D02*
Y-190263D01*
X-313889Y-207763D01*
Y-190263D01*
G01X-301411Y-207763D02*
X-303158Y-207471D01*
X-304686Y-206305D01*
X-305996Y-204555D01*
X-306870Y-202513D01*
X-307306Y-200180D01*
Y-197846D01*
X-306870Y-195513D01*
X-305996Y-193471D01*
X-304686Y-191722D01*
X-303158Y-190555D01*
X-301411Y-190263D01*
X-299665Y-190555D01*
X-298136Y-191722D01*
X-296826Y-193471D01*
X-295952Y-195513D01*
X-295516Y-197846D01*
Y-200180D01*
X-295952Y-202513D01*
X-296826Y-204555D01*
X-298136Y-206305D01*
X-299665Y-207471D01*
X-301411Y-207763D01*
G01X-218861Y-252763D02*
Y-235263D01*
X-221481Y-238763D01*
G01Y-252763D02*
X-216241D01*
G01X-250570Y-190263D02*
X-245111Y-207763D01*
X-239652Y-190263D01*
G01X-223244Y-207763D02*
X-231978D01*
Y-190263D01*
X-223244D01*
G01X-226738Y-198721D02*
X-231978D01*
G01X-214478Y-207763D02*
Y-190263D01*
X-209019D01*
X-207273Y-191138D01*
X-206181Y-192305D01*
X-205744Y-194638D01*
X-206181Y-196972D01*
X-207491Y-198430D01*
X-209019Y-199305D01*
X-214478D01*
G01X-209019D02*
X-205744Y-207763D01*
G01X-192611Y-208346D02*
X-193048Y-208055D01*
Y-207471D01*
X-192611Y-207180D01*
X-192174Y-207471D01*
Y-208055D01*
X-192611Y-208346D01*
G01X-112661Y-235263D02*
Y-252763D01*
G01X-117683Y-235263D02*
X-107639D01*
G01X-100838Y-252763D02*
Y-235263D01*
X-95161Y-249846D01*
X-89484Y-235263D01*
Y-252763D01*
G01X-83120D02*
X-77661Y-235263D01*
X-72202Y-252763D01*
G01X-74168Y-246638D02*
X-81155D01*
G01X-64746Y-250430D02*
X-62999Y-251888D01*
X-61034Y-252763D01*
X-59288D01*
X-57541Y-251888D01*
X-56231Y-250430D01*
X-55576Y-248388D01*
X-56013Y-246347D01*
X-57104Y-244596D01*
X-59069Y-243430D01*
X-61689Y-242846D01*
X-63218Y-241680D01*
X-63873Y-239638D01*
X-63436Y-237596D01*
X-62344Y-236138D01*
X-60816Y-235263D01*
X-59288D01*
X-57759Y-235846D01*
X-56449Y-237305D01*
G01X-47464Y-252763D02*
Y-235263D01*
G01X-39168D02*
X-47464Y-246055D01*
G01X-37858Y-252763D02*
X-43753Y-241097D01*
G01X-125778Y-190263D02*
Y-207763D01*
X-117044D01*
G01X-99981D02*
Y-196097D01*
G01Y-198138D02*
X-100854Y-196972D01*
X-102165Y-196388D01*
X-103693Y-196097D01*
X-105221Y-196680D01*
X-106531Y-197846D01*
X-107405Y-199596D01*
X-107841Y-201930D01*
X-107405Y-204263D01*
X-106531Y-206013D01*
X-105221Y-207180D01*
X-103693Y-207763D01*
X-102165Y-207471D01*
X-100854Y-206597D01*
X-99981Y-205430D01*
G01X-90996Y-213013D02*
X-89686Y-213596D01*
X-87939Y-213013D01*
X-86848Y-211847D01*
X-85974Y-210388D01*
X-84665Y-205722D01*
X-81826Y-196097D01*
G01X-88813D02*
X-84665Y-205722D01*
G01X-72186Y-199888D02*
X-65199D01*
X-65854Y-197846D01*
X-66946Y-196680D01*
X-68474Y-196097D01*
X-70003Y-196388D01*
X-71313Y-197263D01*
X-72186Y-199305D01*
X-72623Y-201055D01*
Y-202805D01*
X-72186Y-204555D01*
X-71094Y-206305D01*
X-69784Y-207471D01*
X-68256Y-207763D01*
X-66728Y-207180D01*
X-65199Y-205430D01*
G01X-54468Y-207763D02*
Y-196097D01*
G01Y-198430D02*
X-53376Y-197263D01*
X-52284Y-196388D01*
X-50756Y-196097D01*
X-49665Y-196388D01*
X-48354Y-197263D01*
G01X-37186Y-205722D02*
X-36094Y-206888D01*
X-34566Y-207763D01*
X-33256D01*
X-31946Y-207180D01*
X-31073Y-206305D01*
X-30636Y-205139D01*
X-30854Y-203388D01*
X-31728Y-202513D01*
X-35658Y-200763D01*
X-36531Y-198721D01*
X-36094Y-197263D01*
X-35221Y-196388D01*
X-33911Y-196097D01*
X-32601Y-196388D01*
X-31291Y-197263D01*
G01X51772Y-235263D02*
Y-252763D01*
X60506D01*
G01X68836Y-235263D02*
Y-247805D01*
X69709Y-250430D01*
X71456Y-252180D01*
X73639Y-252763D01*
X75822Y-252180D01*
X77569Y-250430D01*
X78442Y-247805D01*
Y-235263D01*
G01X95942Y-236722D02*
X94632Y-235846D01*
X93104Y-235263D01*
X91357D01*
X89392Y-236138D01*
X87864Y-237596D01*
X86772Y-239347D01*
X85899Y-242263D01*
X85680Y-244888D01*
X86117Y-247513D01*
X86772Y-249263D01*
X88082Y-251013D01*
X89611Y-252180D01*
X91139Y-252763D01*
X92667D01*
X94196Y-252180D01*
X95506Y-251305D01*
X96598Y-250139D01*
G01X103836Y-252763D02*
Y-235263D01*
G01X112132D02*
X103836Y-246055D01*
G01X113442Y-252763D02*
X107547Y-241097D01*
G01X126139Y-252763D02*
Y-244888D01*
X121772Y-235263D01*
G01X130506D02*
X126139Y-244888D01*
G01X25086Y-207763D02*
Y-190263D01*
X29452D01*
X31199Y-191138D01*
X32509Y-192305D01*
X33601Y-194054D01*
X34474Y-196097D01*
X34692Y-199013D01*
X34474Y-201930D01*
X33601Y-203972D01*
X32509Y-205722D01*
X31199Y-206888D01*
X29452Y-207763D01*
X25086D01*
G01X44114Y-199888D02*
X51101D01*
X50446Y-197846D01*
X49354Y-196680D01*
X47826Y-196097D01*
X46297Y-196388D01*
X44987Y-197263D01*
X44114Y-199305D01*
X43677Y-201055D01*
Y-202805D01*
X44114Y-204555D01*
X45206Y-206305D01*
X46516Y-207471D01*
X48044Y-207763D01*
X49572Y-207180D01*
X51101Y-205430D01*
G01X61614Y-205722D02*
X62706Y-206888D01*
X64234Y-207763D01*
X65544D01*
X66854Y-207180D01*
X67727Y-206305D01*
X68164Y-205139D01*
X67946Y-203388D01*
X67072Y-202513D01*
X63142Y-200763D01*
X62269Y-198721D01*
X62706Y-197263D01*
X63579Y-196388D01*
X64889Y-196097D01*
X66199Y-196388D01*
X67509Y-197263D01*
G01X82389Y-196097D02*
Y-207763D01*
G01Y-191430D02*
X81952Y-191138D01*
Y-190555D01*
X82389Y-190263D01*
X82826Y-190555D01*
Y-191138D01*
X82389Y-191430D01*
G01X96832Y-212138D02*
X98361Y-213305D01*
X100107Y-213596D01*
X101635Y-213305D01*
X102946Y-211847D01*
X103819Y-209805D01*
Y-196097D01*
G01Y-198430D02*
X102946Y-197263D01*
X101635Y-196388D01*
X100107Y-196097D01*
X98361Y-196680D01*
X97269Y-197846D01*
X96395Y-199888D01*
X95959Y-201930D01*
X96177Y-203680D01*
X97051Y-205722D01*
X98361Y-207180D01*
X100107Y-207763D01*
X101417Y-207471D01*
X102946Y-206305D01*
X103819Y-205139D01*
G01X113677Y-207763D02*
Y-196097D01*
G01Y-199013D02*
X114551Y-197555D01*
X115861Y-196388D01*
X117607Y-196097D01*
X119135Y-196388D01*
X120446Y-197555D01*
X121101Y-199596D01*
Y-207763D01*
G01X131614Y-199888D02*
X138601D01*
X137946Y-197846D01*
X136854Y-196680D01*
X135326Y-196097D01*
X133797Y-196388D01*
X132487Y-197263D01*
X131614Y-199305D01*
X131177Y-201055D01*
Y-202805D01*
X131614Y-204555D01*
X132706Y-206305D01*
X134016Y-207471D01*
X135544Y-207763D01*
X137072Y-207180D01*
X138601Y-205430D01*
G01X149332Y-207763D02*
Y-196097D01*
G01Y-198430D02*
X150424Y-197263D01*
X151516Y-196388D01*
X153044Y-196097D01*
X154135Y-196388D01*
X155446Y-197263D01*
G01X196089Y-252763D02*
Y-235263D01*
X193469Y-238763D01*
G01Y-252763D02*
X198709D01*
G01X213589Y-235263D02*
X211842Y-235846D01*
X210532Y-237305D01*
X209659Y-239054D01*
X209004Y-241388D01*
X208786Y-244013D01*
X209004Y-246638D01*
X209659Y-248972D01*
X210532Y-250722D01*
X211842Y-252180D01*
X213589Y-252763D01*
X215335Y-252180D01*
X216646Y-250722D01*
X217519Y-248972D01*
X218174Y-246638D01*
X218392Y-244013D01*
X218174Y-241388D01*
X217519Y-239054D01*
X216646Y-237305D01*
X215335Y-235846D01*
X213589Y-235263D01*
G01X227159Y-253346D02*
X235019Y-235263D01*
G01X248589Y-252763D02*
Y-235263D01*
X245969Y-238763D01*
G01Y-252763D02*
X251209D01*
G01X261941Y-245472D02*
X263469Y-243430D01*
X264779Y-242263D01*
X266526Y-241680D01*
X268054Y-242263D01*
X269146Y-243430D01*
X270019Y-245180D01*
X270237Y-247221D01*
X270019Y-248972D01*
X269146Y-250722D01*
X267835Y-252180D01*
X266307Y-252763D01*
X264561Y-252180D01*
X263032Y-250430D01*
X262159Y-247805D01*
X261941Y-244888D01*
X262377Y-241097D01*
X263032Y-239054D01*
X264124Y-237013D01*
X265652Y-235555D01*
X267181Y-235263D01*
X268709Y-235846D01*
X269801Y-237305D01*
G01X279659Y-253346D02*
X287519Y-235263D01*
G01X296941Y-238180D02*
X298251Y-236430D01*
X299779Y-235555D01*
X301526Y-235263D01*
X303709Y-235846D01*
X305237Y-237305D01*
X305674Y-239054D01*
X305456Y-240805D01*
X304582Y-242263D01*
X300216Y-245180D01*
X298251Y-247221D01*
X296941Y-250139D01*
X296504Y-252763D01*
X305674D01*
G01X318589Y-235263D02*
X316842Y-235846D01*
X315532Y-237305D01*
X314659Y-239054D01*
X314004Y-241388D01*
X313786Y-244013D01*
X314004Y-246638D01*
X314659Y-248972D01*
X315532Y-250722D01*
X316842Y-252180D01*
X318589Y-252763D01*
X320335Y-252180D01*
X321646Y-250722D01*
X322519Y-248972D01*
X323174Y-246638D01*
X323392Y-244013D01*
X323174Y-241388D01*
X322519Y-239054D01*
X321646Y-237305D01*
X320335Y-235846D01*
X318589Y-235263D01*
G01X336089Y-252763D02*
Y-235263D01*
X333469Y-238763D01*
G01Y-252763D02*
X338709D01*
G01X349441Y-238180D02*
X350751Y-236430D01*
X352279Y-235555D01*
X354026Y-235263D01*
X356209Y-235846D01*
X357737Y-237305D01*
X358174Y-239054D01*
X357956Y-240805D01*
X357082Y-242263D01*
X352716Y-245180D01*
X350751Y-247221D01*
X349441Y-250139D01*
X349004Y-252763D01*
X358174D01*
G01X243786Y-207763D02*
Y-190263D01*
X248152D01*
X249899Y-191138D01*
X251209Y-192305D01*
X252301Y-194054D01*
X253174Y-196097D01*
X253392Y-199013D01*
X253174Y-201930D01*
X252301Y-203972D01*
X251209Y-205722D01*
X249899Y-206888D01*
X248152Y-207763D01*
X243786D01*
G01X270019D02*
Y-196097D01*
G01Y-198138D02*
X269146Y-196972D01*
X267835Y-196388D01*
X266307Y-196097D01*
X264779Y-196680D01*
X263469Y-197846D01*
X262595Y-199596D01*
X262159Y-201930D01*
X262595Y-204263D01*
X263469Y-206013D01*
X264779Y-207180D01*
X266307Y-207763D01*
X267835Y-207471D01*
X269146Y-206597D01*
X270019Y-205430D01*
G01X283589Y-190263D02*
Y-207763D01*
G01X280532Y-196097D02*
X286646D01*
G01X297814Y-199888D02*
X304801D01*
X304146Y-197846D01*
X303054Y-196680D01*
X301526Y-196097D01*
X299997Y-196388D01*
X298687Y-197263D01*
X297814Y-199305D01*
X297377Y-201055D01*
Y-202805D01*
X297814Y-204555D01*
X298906Y-206305D01*
X300216Y-207471D01*
X301744Y-207763D01*
X303272Y-207180D01*
X304801Y-205430D01*
G54D57*
X129310Y186223D03*
Y204175D03*
G54D66*
X193000Y130850D03*
Y146350D03*
X274405Y63139D03*
Y47639D03*
G54D75*
X194548Y827952D03*
Y837401D03*
Y846849D03*
G54D39*
X33253Y486907D03*
X25653D03*
X33250Y479024D03*
X25650D03*
X245837Y83579D03*
X253437D03*
X302287Y456235D03*
X294687D03*
X653800Y520900D03*
X646200D03*
X653819Y513168D03*
X646219D03*
G54D84*
X510634Y403425D03*
Y408425D03*
Y413425D03*
X530634D03*
Y408425D03*
Y403425D03*
X510634Y418425D03*
X530634D03*
G54D48*
X62540Y665912D03*
X98941Y207700D03*
X245067Y69296D03*
X272170Y794774D03*
X526900Y397400D03*
G54D49*
X52900Y645300D03*
Y634300D03*
Y748300D03*
Y759300D03*
X205600Y135800D03*
Y146800D03*
X294751Y448610D03*
Y437610D03*
X303549Y448556D03*
Y437556D03*
G54D85*
X513500Y396160D03*
Y393600D03*
Y391040D03*
X520900D03*
Y393600D03*
Y396160D03*
G54D76*
X226090Y82133D03*
G54D67*
X166649Y132747D03*
G54D58*
X83800Y188800D03*
X111482Y202800D03*
X113815Y194333D03*
X122400Y199000D03*
X83500Y653600D03*
Y640044D03*
X84900Y747900D03*
X85300Y755100D03*
X85000Y775900D03*
X84100Y769000D03*
X197900Y82000D03*
X201614Y89932D03*
X170302Y147100D03*
X158100Y166800D03*
X167015Y167633D03*
X163550Y179657D03*
X242488Y88466D03*
X503300Y539700D03*
G54D86*
X716535Y39370D03*
G54D68*
X164396Y151107D03*
Y165087D03*
X170302D03*
Y151107D03*
G54D77*
X246455Y107157D03*
G54D59*
X104382Y212614D03*
X99525Y212610D03*
X212700Y129700D03*
X168084Y172055D03*
X212492Y403033D03*
X217363Y401778D03*
X185934Y470229D03*
X203439Y459352D03*
X194624Y421463D03*
X190765Y470328D03*
X264353Y484934D03*
X222577Y522519D03*
X341430Y463151D03*
X371408Y393555D03*
X366586D03*
X361719D03*
G54D78*
X246455Y109657D03*
G54D87*
X672257Y523769D03*
G54D69*
X160359Y154160D03*
Y156128D03*
Y158097D03*
Y160066D03*
Y162034D03*
X174339D03*
Y160066D03*
Y158097D03*
Y156128D03*
Y154160D03*
G54D79*
X220569Y204940D03*
X223129D03*
X225689D03*
X228249D03*
Y188760D03*
X225689D03*
X223129D03*
X220569D03*
X237750Y428000D03*
X235250D03*
X232750D03*
X230250D03*
X227750D03*
X225250D03*
X222750D03*
X220250D03*
Y448600D03*
X222750D03*
X225250D03*
X227750D03*
X230250D03*
X232750D03*
X235250D03*
X237750D03*
X228249Y755690D03*
X225689D03*
X223129D03*
X220569D03*
Y771870D03*
X223129D03*
X225689D03*
X228249D03*
G54D88*
X662514Y518651D03*
Y521210D03*
Y523769D03*
Y526328D03*
Y528887D03*
X682000D03*
Y526328D03*
Y523769D03*
Y521210D03*
Y518651D03*
G54D89*
X667139Y533512D03*
X669698D03*
X672257D03*
X674816D03*
X677375D03*
Y514026D03*
X674816D03*
X672257D03*
X669698D03*
X667139D03*
M02*
